# Altium SchDoc records: MAC.SchDoc
|HEADER=Protel for Windows - Schematic Capture Binary File Version 5.0|Weight=704|MinorVersion=2
|RECORD=31|FontIdCount=8|Size1=10|FontName1=Times New Roman|Size2=10|Underline2=T|FontName2=Times New Roman|Size3=12|FontName3=Arial|Size4=14|FontName4=Arial|Size5=24|FontName5=Times New Roman|Size6=8|FontName6=Arial|Size7=10|FontName7=Arial|Size8=12|Underline8=T|FontName8=Arial|UseMBCS=T|IsBOC=T|HotSpotGridOn=T|HotSpotGridSize=4|SheetStyle=12|SystemFont=7|BorderOn=T|SheetNumberSpaceSize=12|AreaColor=16317695|SnapGridOn=T|SnapGridSize=10|VisibleGridOn=T|VisibleGridSize=10|CustomX=2338|CustomX_Frac=58268|CustomY=1653|CustomY_Frac=54331|CustomXZones=8|CustomYZones=6|CustomMarginWidth=19|CustomMarginWidth_Frac=80000|ShowTemplateGraphics=T|TemplateFileName=C:\Users\<user>\Documents\Altium\AD20\Templates\Timecard.SchDot|Display_Unit=0
|RECORD=39|IsNotAccesible=T|OwnerPartId=-1|FileName=C:\Users\<user>\Documents\Altium\AD20\Templates\Timecard.SchDot
|RECORD=4|OwnerIndex=1|OwnerPartId=-1|Location.X=1594|Location.Y=39|Color=8388608|FontID=8|Text=timingcard.com|URL=http://timingcard.com
|RECORD=6|OwnerIndex=1|IndexInSheet=1|OwnerPartId=-1|LocationCount=2|X1=1680|Y1=35|X2=1576|Y2=35
|RECORD=4|OwnerIndex=1|IndexInSheet=2|OwnerPartId=-1|Location.X=1614|Location.X_Frac=42446|Location.Y=19|Location.Y_Frac=96838|FontID=3|Text==SheetNumber
|RECORD=4|OwnerIndex=1|IndexInSheet=3|OwnerPartId=-1|Location.X=1581|Location.X_Frac=42446|Location.Y=29|Location.Y_Frac=96838|Justification=3|FontID=6|Text=SHEET
|RECORD=4|OwnerIndex=1|IndexInSheet=4|OwnerPartId=-1|Location.X=1639|Location.X_Frac=42446|Location.Y=29|Location.Y_Frac=96838|Justification=3|FontID=6|Text=OF
|RECORD=6|OwnerIndex=1|IndexInSheet=5|OwnerPartId=-1|LineWidth=1|LocationCount=2|X1=1679|X1_Frac=42446|Y1=105|Y1_Frac=96838|X2=1576|Y2=106
|RECORD=4|OwnerIndex=1|IndexInSheet=6|OwnerPartId=-1|Location.X=1658|Location.Y=20|FontID=3|Text==SheetTotal
|RECORD=30|OwnerIndex=1|IndexInSheet=7|OwnerPartId=-1|Location.X=1578|Location.Y=53|Corner.X=1673|Corner.X_Frac=88801|Corner.Y=103|KeepAspect=T|FileName=C:\Users\<user>\Desktop\Timecard Logo\TIMECARD.jpg
|RECORD=6|OwnerIndex=1|IndexInSheet=8|OwnerPartId=-1|LineWidth=1|LocationCount=2|X1=1576|X1_Frac=3162|Y1=105|Y1_Frac=42446|X2=1576|Y2=20
|RECORD=6|OwnerIndex=1|IndexInSheet=9|OwnerPartId=-1|LocationCount=2|X1=1680|Y1=51|X2=1576|Y2=51
|RECORD=41|IndexInSheet=1|OwnerPartId=-1|Color=8388608|FontID=1|IsHidden=T|Text=*|Name=CurrentTime|ReadOnlyState=1
|RECORD=41|IndexInSheet=2|OwnerPartId=-1|Color=8388608|FontID=1|IsHidden=T|Text=*|Name=CurrentDate|ReadOnlyState=1
|RECORD=41|IndexInSheet=3|OwnerPartId=-1|Color=8388608|FontID=1|IsHidden=T|Text=*|Name=Time|ReadOnlyState=1
|RECORD=41|IndexInSheet=4|OwnerPartId=-1|Color=8388608|FontID=1|IsHidden=T|Text=*|Name=Date|ReadOnlyState=1
|RECORD=41|IndexInSheet=5|OwnerPartId=-1|Color=8388608|FontID=1|IsHidden=T|Text=*|Name=DocumentFullPathAndName|ReadOnlyState=1
|RECORD=41|IndexInSheet=6|OwnerPartId=-1|Color=8388608|FontID=1|IsHidden=T|Text=*|Name=DocumentName|ReadOnlyState=1
|RECORD=41|IndexInSheet=7|OwnerPartId=-1|Color=8388608|FontID=1|IsHidden=T|Text=*|Name=ModifiedDate|ReadOnlyState=1
|RECORD=41|IndexInSheet=8|OwnerPartId=-1|Color=8388608|FontID=1|IsHidden=T|Text=*|Name=ApprovedBy|ReadOnlyState=1
|RECORD=41|IndexInSheet=9|OwnerPartId=-1|Color=8388608|FontID=1|IsHidden=T|Text=*|Name=CheckedBy|ReadOnlyState=1
|RECORD=41|IndexInSheet=10|OwnerPartId=-1|Color=8388608|FontID=1|IsHidden=T|Text=<name>|Name=Author|ReadOnlyState=1
|RECORD=41|IndexInSheet=11|OwnerPartId=-1|Color=8388608|FontID=1|IsHidden=T|Text=*|Name=CompanyName|ReadOnlyState=1
|RECORD=41|IndexInSheet=12|OwnerPartId=-1|Color=8388608|FontID=1|IsHidden=T|Text=*|Name=DrawnBy|ReadOnlyState=1
|RECORD=41|IndexInSheet=13|OwnerPartId=-1|Color=8388608|FontID=1|IsHidden=T|Text=*|Name=Engineer|ReadOnlyState=1
|RECORD=41|IndexInSheet=14|OwnerPartId=-1|Color=8388608|FontID=1|IsHidden=T|Text=*|Name=Organization|ReadOnlyState=1
|RECORD=41|IndexInSheet=15|OwnerPartId=-1|Color=8388608|FontID=1|IsHidden=T|Text=*|Name=Address1|ReadOnlyState=1
|RECORD=41|IndexInSheet=16|OwnerPartId=-1|Color=8388608|FontID=1|IsHidden=T|Text=*|Name=Address2|ReadOnlyState=1
|RECORD=41|IndexInSheet=17|OwnerPartId=-1|Color=8388608|FontID=1|IsHidden=T|Text=*|Name=Address3|ReadOnlyState=1
|RECORD=41|IndexInSheet=18|OwnerPartId=-1|Color=8388608|FontID=1|IsHidden=T|Text=*|Name=Address4|ReadOnlyState=1
|RECORD=41|IndexInSheet=19|OwnerPartId=-1|Color=8388608|FontID=1|IsHidden=T|Text=Grandmaster MAC & Clock Generation|Name=Title|ReadOnlyState=1
|RECORD=41|IndexInSheet=20|OwnerPartId=-1|Color=8388608|FontID=1|IsHidden=T|Text=*|Name=DocumentNumber|ReadOnlyState=1
|RECORD=41|IndexInSheet=21|OwnerPartId=-1|Color=8388608|FontID=1|IsHidden=T|Text=A|Name=Revision|ReadOnlyState=1
|RECORD=41|IndexInSheet=22|OwnerPartId=-1|Color=8388608|FontID=1|IsHidden=T|Text=6|Name=SheetNumber|ReadOnlyState=1
|RECORD=41|IndexInSheet=23|OwnerPartId=-1|Color=8388608|FontID=1|IsHidden=T|Text=7|Name=SheetTotal|ReadOnlyState=1
|RECORD=41|IndexInSheet=24|OwnerPartId=-1|Color=8388608|FontID=1|IsHidden=T|Text=*|Name=Rule|ReadOnlyState=1
|RECORD=41|IndexInSheet=25|OwnerPartId=-1|Color=8388608|FontID=1|IsHidden=T|Text=*|Name=ImagePath|ReadOnlyState=1
|RECORD=41|IndexInSheet=26|OwnerPartId=-1|Color=8388608|FontID=1|IsHidden=T|Text=*|Name=ProjectName|ReadOnlyState=1
|RECORD=41|IndexInSheet=27|OwnerPartId=-1|Color=8388608|FontID=1|IsHidden=T|Text=*|Name=Application_BuildNumber|ReadOnlyState=1
|RECORD=41|IndexInSheet=28|OwnerPartId=-1|Location.X=21474|Location.X_Frac=83647|Location.Y=21464|Location.Y_Frac=83647|Color=8388608|FontID=1|IsHidden=T|Text=01910|Name=Customer
|RECORD=41|IndexInSheet=29|OwnerPartId=-1|Location.X=1000|Location.Y=10|Color=8388608|FontID=1|IsHidden=T|Text=*|Name=DocStatus
|RECORD=17|IndexInSheet=30|OwnerPartId=-1|ShowNetName=T|Location.X=1020|Location.Y=950|Color=255|FontID=1|Text=MAC_TX|IsCrossSheetConnector=T
|RECORD=17|IndexInSheet=31|OwnerPartId=-1|ShowNetName=T|Location.X=1020|Location.Y=940|Color=255|FontID=1|Text=MAC_RX|IsCrossSheetConnector=T
|RECORD=17|IndexInSheet=32|OwnerPartId=-1|ShowNetName=T|Location.X=1020|Location.Y=930|Color=255|FontID=1|Text=MAC_BITE|IsCrossSheetConnector=T
|RECORD=17|IndexInSheet=33|OwnerPartId=-1|ShowNetName=T|Location.X=720|Location.Y=930|Orientation=2|Color=255|FontID=1|Text=MAC_RF_OUT|IsCrossSheetConnector=T
|RECORD=17|IndexInSheet=34|OwnerPartId=-1|ShowNetName=T|Location.X=720|Location.Y=950|Orientation=2|Color=255|FontID=1|Text=MAC_FREQ_CTRL|IsCrossSheetConnector=T
|RECORD=22|IndexInSheet=35|OwnerPartId=-1|Location.X=780|Location.Y=800|Color=255|Orientation=1|Symbol=Thin Cross|IsActive=T|SuppressAll=T
|RECORD=22|IndexInSheet=36|OwnerPartId=-1|Location.X=780|Location.Y=790|Color=255|Orientation=1|Symbol=Thin Cross|IsActive=T|SuppressAll=T
|RECORD=22|IndexInSheet=37|OwnerPartId=-1|Location.X=780|Location.Y=780|Color=255|Orientation=1|Symbol=Thin Cross|IsActive=T|SuppressAll=T
|RECORD=22|IndexInSheet=38|OwnerPartId=-1|Location.X=780|Location.Y=770|Color=255|Orientation=1|Symbol=Thin Cross|IsActive=T|SuppressAll=T
|RECORD=22|IndexInSheet=39|OwnerPartId=-1|Location.X=780|Location.Y=760|Color=255|Orientation=1|Symbol=Thin Cross|IsActive=T|SuppressAll=T
|RECORD=22|IndexInSheet=40|OwnerPartId=-1|Location.X=780|Location.Y=750|Color=255|Orientation=1|Symbol=Thin Cross|IsActive=T|SuppressAll=T
|RECORD=22|IndexInSheet=41|OwnerPartId=-1|Location.X=780|Location.Y=740|Color=255|Orientation=1|Symbol=Thin Cross|IsActive=T|SuppressAll=T
|RECORD=17|IndexInSheet=42|OwnerPartId=-1|ShowNetName=T|Location.X=700|Location.Y=570|Orientation=2|Color=255|FontID=1|Text=FPGA_MAC_PPS_IN0-|IsCrossSheetConnector=T
|RECORD=17|IndexInSheet=43|OwnerPartId=-1|ShowNetName=T|Location.X=1020|Location.Y=850|Color=255|FontID=1|Text=MAC_USB+|IsCrossSheetConnector=T
|RECORD=17|IndexInSheet=44|OwnerPartId=-1|ShowNetName=T|Location.X=1020|Location.Y=840|Color=255|FontID=1|Text=MAC_USB-|IsCrossSheetConnector=T
|RECORD=17|IndexInSheet=45|OwnerPartId=-1|ShowNetName=T|Location.X=1020|Location.Y=830|Color=255|FontID=1|Text=MAC_USB_PWR|IsCrossSheetConnector=T
|RECORD=17|IndexInSheet=46|OwnerPartId=-1|ShowNetName=T|Location.X=680|Location.Y=370|Orientation=2|Color=255|FontID=1|Text=MAC_PPS_OUT+|IsCrossSheetConnector=T
|RECORD=17|IndexInSheet=47|OwnerPartId=-1|ShowNetName=T|Location.X=680|Location.Y=310|Orientation=2|Color=255|FontID=1|Text=MAC_PPS_OUT-|IsCrossSheetConnector=T
|RECORD=17|IndexInSheet=48|OwnerPartId=-1|ShowNetName=T|Location.X=1020|Location.Y=780|Color=255|FontID=1|Text=MAC_ALARM|IsCrossSheetConnector=T
|RECORD=17|IndexInSheet=49|OwnerPartId=-1|Style=4|ShowNetName=T|Location.X=980|Location.Y=730|Orientation=3|Color=128|FontID=1|Text=GND
|RECORD=17|IndexInSheet=50|OwnerPartId=-1|Style=4|ShowNetName=T|Location.X=750|Location.Y=900|Orientation=3|Color=128|FontID=1|Text=GND
|RECORD=17|IndexInSheet=51|OwnerPartId=-1|ShowNetName=T|Location.X=1150|Location.Y=920|Orientation=1|Color=128|FontID=1|Text=+5.0V
|RECORD=17|IndexInSheet=52|OwnerPartId=-1|Style=4|ShowNetName=T|Location.X=1150|Location.Y=870|Orientation=3|Color=128|FontID=1|Text=GND
|RECORD=4|IndexInSheet=53|OwnerPartId=-1|Location.X=850|Location.Y=1000|Color=8388608|FontID=5|Text=MAC
|RECORD=1|LibReference=CAP_0805_10UF_25V|ComponentDescription=CAP, CER, 10.UF, 25V, 10%, X5R, 0805|PartCount=2|DisplayModeCount=1|IndexInSheet=54|OwnerPartId=-1|Location.X=1080|Location.Y=860|CurrentPartId=1|LibraryPath=*|SourceLibraryName=Capacitors.IntLib|TargetFileName=*|AreaColor=11599871|Color=128|PartIDLocked=F|DesignItemId=CAP_0805_10UF_25V|AllPinCount=2
|RECORD=41|OwnerIndex=65|OwnerPartId=-1|Location.X=1080|Location.Y=860|Color=8388608|FontID=3|IsHidden=T|Text=TAIYO YUDEN|Name=MFG NAME
|RECORD=41|OwnerIndex=65|IndexInSheet=1|OwnerPartId=-1|Location.X=1080|Location.Y=860|Color=8388608|FontID=3|IsHidden=T|Text=TMK212BBJ106KG-T|Name=MFG PART NUM
|RECORD=41|OwnerIndex=65|IndexInSheet=2|OwnerPartId=-1|Location.X=1080|Location.Y=860|Color=8388608|FontID=3|IsHidden=T|Text=10/23/2013|Name=MODIFY DATE
|RECORD=41|OwnerIndex=65|IndexInSheet=3|OwnerPartId=-1|Location.X=1080|Location.Y=860|Color=8388608|FontID=3|IsHidden=T|Text=CAP, CER|Name=CATEGORY
|RECORD=41|OwnerIndex=65|IndexInSheet=4|OwnerPartId=-1|Location.X=1078|Location.Y=872|Location.Y_Frac=50000|Color=8388608|FontID=3|IsHidden=T|Text=4/11/2006 3:37:28 PM|Name=Date
|RECORD=41|OwnerIndex=65|IndexInSheet=5|OwnerPartId=-1|Location.X=1086|Location.Y=934|Location.Y_Frac=48252|Color=8388608|FontID=3|IsHidden=T|Text=*|Name=SHEETPART
|RECORD=41|OwnerIndex=65|IndexInSheet=6|OwnerPartId=-1|Location.X=1086|Location.Y=934|Location.Y_Frac=48252|Color=8388608|FontID=3|IsHidden=T|Text=10%|Name=P1
|RECORD=41|OwnerIndex=65|IndexInSheet=7|OwnerPartId=-1|Location.X=1086|Location.Y=934|Location.Y_Frac=48252|Color=8388608|FontID=3|IsHidden=T|Text=85C|Name=MAXTEMP
|RECORD=41|OwnerIndex=65|IndexInSheet=8|OwnerPartId=-1|Location.X=1086|Location.Y=934|Location.Y_Frac=48252|Color=8388608|FontID=3|IsHidden=T|Text=-55C|Name=MINTEMP
|RECORD=41|OwnerIndex=65|IndexInSheet=9|OwnerPartId=-1|Location.X=1086|Location.Y=934|Location.Y_Frac=48252|Color=8388608|FontID=3|IsHidden=T|Name=OTHER
|RECORD=41|OwnerIndex=65|IndexInSheet=10|OwnerPartId=-1|Location.X=1086|Location.Y=934|Location.Y_Frac=48252|Color=8388608|FontID=3|IsHidden=T|Text=25V|Name=P2
|RECORD=41|OwnerIndex=65|IndexInSheet=11|OwnerPartId=-1|Location.X=1086|Location.Y=934|Location.Y_Frac=48252|Color=8388608|FontID=3|IsHidden=T|Text=X5R|Name=P3
|RECORD=41|OwnerIndex=65|IndexInSheet=12|OwnerPartId=-1|Location.X=1086|Location.Y=934|Location.Y_Frac=48252|Color=8388608|FontID=3|IsHidden=T|Text=0805|Name=Size
|RECORD=41|OwnerIndex=65|IndexInSheet=13|OwnerPartId=-1|Location.X=1086|Location.Y=934|Location.Y_Frac=48252|Color=8388608|FontID=3|IsHidden=T|Name=SUB
|RECORD=41|OwnerIndex=65|IndexInSheet=14|OwnerPartId=-1|Location.X=1086|Location.Y=934|Location.Y_Frac=48252|Color=8388608|FontID=1|IsHidden=T|Text=CAP, CER, 10.UF, 10V, 10%, X5R, 0805|Name=DESC
|RECORD=41|OwnerIndex=65|IndexInSheet=15|OwnerPartId=-1|Location.X=1086|Location.Y=933|Location.Y_Frac=98252|Color=8388608|FontID=1|IsHidden=T|Text=MOUSER|Name=Supplier 1|ReadOnlyState=1
|RECORD=41|OwnerIndex=65|IndexInSheet=16|OwnerPartId=-1|Location.X=1086|Location.Y=933|Location.Y_Frac=98252|Color=8388608|FontID=1|IsHidden=T|Text=963-TMK212BBJ106KG-T|Name=Supplier Part Number 1|ReadOnlyState=1
|RECORD=41|OwnerIndex=65|IndexInSheet=17|OwnerPartId=-1|Location.X=1110|Location.Y=890|Color=8388608|FontID=3|Text=10uF|Name=VALUE
|RECORD=2|OwnerIndex=65|OwnerPartId=1|FormalType=1|Electrical=4|PinConglomerate=35|PinLength=10|Location.X=1100|Location.Y=890|Name=2|Designator=2|SwapIdPin=2|SwapIDPart=1|PinPropagationDelay=0.000000E+000
|RECORD=2|OwnerIndex=65|OwnerPartId=1|FormalType=1|Electrical=4|PinConglomerate=33|PinLength=10|Location.X=1100|Location.Y=900|Name=1|Designator=1|SwapIdPin=1|SwapIDPart=1|PinPropagationDelay=0.000000E+000
|RECORD=13|OwnerIndex=65|IsNotAccesible=T|IndexInSheet=20|OwnerPartId=1|Location.X=1100|Location.Y=892|Location.Y_Frac=50000|Corner.X=1100|Corner.Y=890|LineWidth=1|Color=16711680
|RECORD=13|OwnerIndex=65|IsNotAccesible=T|IndexInSheet=21|OwnerPartId=1|Location.X=1100|Location.Y=900|Corner.X=1100|Corner.Y=897|Corner.Y_Frac=50000|LineWidth=1|Color=16711680
|RECORD=13|OwnerIndex=65|IsNotAccesible=T|IndexInSheet=22|OwnerPartId=1|Location.X=1105|Location.Y=892|Location.Y_Frac=50000|Corner.X=1095|Corner.Y=892|Corner.Y_Frac=50000|LineWidth=1|Color=16711680
|RECORD=13|OwnerIndex=65|IsNotAccesible=T|IndexInSheet=23|OwnerPartId=1|Location.X=1105|Location.Y=897|Location.Y_Frac=50000|Corner.X=1095|Corner.Y=897|Corner.Y_Frac=50000|LineWidth=1|Color=16711680
|RECORD=41|OwnerIndex=65|IndexInSheet=24|OwnerPartId=-1|Location.X=1086|Location.Y=933|Location.Y_Frac=98951|Color=8388608|FontID=1|IsHidden=T|Text=<VALENTIUM>|Name=VALENTIUM PART NUM
|RECORD=34|OwnerIndex=65|IndexInSheet=-1|OwnerPartId=-1|Location.X=1110|Location.Y=900|Color=8388608|FontID=4|Text=C62|Name=Designator|ReadOnlyState=1
|RECORD=41|OwnerIndex=65|IndexInSheet=-1|OwnerPartId=-1|Location.X=1107|Location.X_Frac=50000|Location.Y=855|Color=8388608|FontID=3|IsHidden=T|Text=CAP_0805_10UF_25V|Name=Comment
|RECORD=44|OwnerIndex=65
|RECORD=45|OwnerIndex=95|IndexInSheet=-1|Description=Chip Capacitor, 0805, 2-Leads, Body 2.00x1.25mm, IPC Medium Density|UseComponentLibrary=T|ModelName=CAPC2012X14N|ModelType=PCBLIB|DatafileCount=1|ModelDatafileEntity0=CAPC2012X14N|ModelDatafileKind0=PCBLib|IsCurrent=T|DatalinksLocked=T|DatabaseDatalinksLocked=T|IntegratedModel=T|DatabaseModel=T
|RECORD=46|OwnerIndex=96
|RECORD=48|OwnerIndex=96
|RECORD=1|LibReference=MAC-SA5X|ComponentDescription=MOD, MAC, MAC-SA5X, ATOMIC CLOCK|PartCount=3|DisplayModeCount=1|IndexInSheet=55|OwnerPartId=-1|Location.X=870|Location.Y=940|CurrentPartId=1|LibraryPath=*|SourceLibraryName=Modules.IntLib|TargetFileName=*|AreaColor=11599871|Color=128|PartIDLocked=F|DesignItemId=MAC-SA5X|AllPinCount=28
|RECORD=41|OwnerIndex=99|OwnerPartId=-1|Location.X=870|Location.Y=940|Color=8388608|FontID=3|IsHidden=T|Text=3/22/2006 1:36:44 PM|Name=MODIFY DATE
|RECORD=41|OwnerIndex=99|IndexInSheet=1|OwnerPartId=-1|Location.X=870|Location.Y=940|Color=8388608|FontID=3|IsHidden=T|Text=MAC-SA5X|Name=MFG PART NUM
|RECORD=41|OwnerIndex=99|IndexInSheet=2|OwnerPartId=-1|Location.X=838|Location.Y=972|Color=8388608|FontID=3|IsHidden=T|Text=MOD|Name=CATEGORY
|RECORD=41|OwnerIndex=99|IndexInSheet=3|OwnerPartId=-1|Location.X=838|Location.Y=972|Color=8388608|FontID=3|IsHidden=T|Name=DATE
|RECORD=41|OwnerIndex=99|IndexInSheet=4|OwnerPartId=-1|Location.X=838|Location.Y=972|Color=8388608|FontID=3|IsHidden=T|Text=MICROCHIP|Name=MFG NAME
|RECORD=41|OwnerIndex=99|IndexInSheet=5|OwnerPartId=-1|Location.X=838|Location.Y=972|Color=8388608|FontID=3|IsHidden=T|Text=85C|Name=MAXTEMP
|RECORD=41|OwnerIndex=99|IndexInSheet=6|OwnerPartId=-1|Location.X=838|Location.Y=972|Color=8388608|FontID=3|IsHidden=T|Text=-40C|Name=MINTEMP
|RECORD=41|OwnerIndex=99|IndexInSheet=7|OwnerPartId=-1|Location.X=838|Location.Y=972|Color=8388608|FontID=3|IsHidden=T|Text=AEC-Q200|Name=OTHER
|RECORD=41|OwnerIndex=99|IndexInSheet=8|OwnerPartId=-1|Location.X=838|Location.Y=972|Color=8388608|FontID=3|IsHidden=T|Text=ATOMIC CLOCK|Name=P1
|RECORD=41|OwnerIndex=99|IndexInSheet=9|OwnerPartId=-1|Location.X=838|Location.Y=972|Color=8388608|FontID=3|IsHidden=T|Name=P2
|RECORD=41|OwnerIndex=99|IndexInSheet=10|OwnerPartId=-1|Location.X=838|Location.Y=972|Color=8388608|FontID=3|IsHidden=T|Name=P3
|RECORD=41|OwnerIndex=99|IndexInSheet=11|OwnerPartId=-1|Location.X=838|Location.Y=972|Color=8388608|FontID=3|IsHidden=T|Name=SIZE
|RECORD=41|OwnerIndex=99|IndexInSheet=12|OwnerPartId=-1|Location.X=838|Location.Y=972|Color=8388608|FontID=3|IsHidden=T|Name=SUB
|RECORD=41|OwnerIndex=99|IndexInSheet=13|OwnerPartId=-1|Location.X=838|Location.Y=768|Color=8388608|FontID=1|IsHidden=T|Text=*|Name=SHEETPART
|RECORD=41|OwnerIndex=99|IndexInSheet=14|OwnerPartId=-1|Location.X=838|Location.Y=972|Color=8388608|FontID=1|IsHidden=T|Text=MOD, MAC, MAC-SA5X, ATOMIC CLOCK|Name=DESC
|RECORD=41|OwnerIndex=99|IndexInSheet=15|OwnerPartId=-1|Location.X=828|Location.Y=972|Color=8388608|FontID=1|IsHidden=T|Text=<V PART NUM>|Name=VELENTIUM PART NUM
|RECORD=14|OwnerIndex=99|IsNotAccesible=T|IndexInSheet=16|OwnerPartId=1|Location.X=800|Location.Y=910|Corner.X=950|Corner.Y=960|Color=128|AreaColor=11599871|IsSolid=T
|RECORD=2|OwnerIndex=99|OwnerPartId=1|FormalType=1|Electrical=4|PinConglomerate=58|PinLength=30|Location.X=800|Location.Y=950|Name=FREQ CTRL IN|Designator=P1|SwapIDPart=Ž&Ž||PinPropagationDelay=0.000000E+000
|RECORD=2|OwnerIndex=99|OwnerPartId=1|FormalType=1|Electrical=4|PinConglomerate=58|PinLength=30|Location.X=800|Location.Y=940|Name=GND (CASE)|Designator=P2|SwapIDPart=Ž&Ž||PinPropagationDelay=0.000000E+000
|RECORD=2|OwnerIndex=99|OwnerPartId=1|FormalType=1|Electrical=4|PinConglomerate=58|PinLength=30|Location.X=800|Location.Y=930|Name=RF OUT|Designator=P3|SwapIDPart=Ž&Ž||PinPropagationDelay=0.000000E+000
|RECORD=2|OwnerIndex=99|OwnerPartId=1|FormalType=1|Electrical=4|PinConglomerate=58|PinLength=30|Location.X=800|Location.Y=920|Name=GND (SUPPLY & SIGNAL)|Designator=P4|SwapIDPart=Ž&Ž||PinPropagationDelay=0.000000E+000
|RECORD=2|OwnerIndex=99|OwnerPartId=1|FormalType=1|Electrical=4|PinConglomerate=56|PinLength=30|Location.X=950|Location.Y=920|Name=VCC|Designator=P5|SwapIDPart=Ž&Ž||PinPropagationDelay=0.000000E+000
|RECORD=2|OwnerIndex=99|OwnerPartId=1|FormalType=1|Electrical=4|PinConglomerate=56|PinLength=30|Location.X=950|Location.Y=930|Name=BITE|Designator=P6|SwapIDPart=Ž&Ž||PinPropagationDelay=0.000000E+000
|RECORD=2|OwnerIndex=99|OwnerPartId=1|FormalType=1|Electrical=4|PinConglomerate=56|PinLength=30|Location.X=950|Location.Y=940|Name=RS-232 TX|Designator=P7|SwapIDPart=Ž&Ž||PinPropagationDelay=0.000000E+000
|RECORD=2|OwnerIndex=99|OwnerPartId=1|FormalType=1|Electrical=4|PinConglomerate=56|PinLength=30|Location.X=950|Location.Y=950|Name=RS-232 RX|Designator=P8|SwapIDPart=Ž&Ž||PinPropagationDelay=0.000000E+000
|RECORD=41|OwnerIndex=99|IndexInSheet=25|OwnerPartId=-1|Location.X=800|Location.Y=898|Color=8388608|FontID=3|Text=RV-3049-C3|Name=VALUE
|RECORD=14|OwnerIndex=99|IsNotAccesible=T|IndexInSheet=26|OwnerPartId=2|Location.X=810|Location.Y=870|Corner.X=930|Corner.Y=1000|Color=128|AreaColor=11599871|IsSolid=T
|RECORD=2|OwnerIndex=99|OwnerPartId=2|FormalType=1|Electrical=4|PinConglomerate=58|PinLength=30|Location.X=810|Location.Y=990|Name=PPS-IN 1+|Designator=1|SwapIDPart=Ž&Ž||PinPropagationDelay=0.000000E+000
|RECORD=2|OwnerIndex=99|OwnerPartId=2|FormalType=1|Electrical=4|PinConglomerate=56|PinLength=30|Location.X=930|Location.Y=990|Name=USB DATA +|Designator=2|SwapIDPart=Ž&Ž||PinPropagationDelay=0.000000E+000
|RECORD=2|OwnerIndex=99|OwnerPartId=2|FormalType=1|Electrical=4|PinConglomerate=58|PinLength=30|Location.X=810|Location.Y=980|Name=PPS-IN 1-|Designator=3|SwapIDPart=Ž&Ž||PinPropagationDelay=0.000000E+000
|RECORD=2|OwnerIndex=99|OwnerPartId=2|FormalType=1|Electrical=4|PinConglomerate=56|PinLength=30|Location.X=930|Location.Y=980|Name=USB DATA -|Designator=4|SwapIDPart=Ž&Ž||PinPropagationDelay=0.000000E+000
|RECORD=2|OwnerIndex=99|OwnerPartId=2|FormalType=1|Electrical=4|PinConglomerate=58|PinLength=30|Location.X=810|Location.Y=970|Name=PPS-IN 0+|Designator=5|SwapIDPart=Ž&Ž||PinPropagationDelay=0.000000E+000
|RECORD=2|OwnerIndex=99|OwnerPartId=2|FormalType=1|Electrical=4|PinConglomerate=56|PinLength=30|Location.X=930|Location.Y=970|Name=USB POWER|Designator=6|SwapIDPart=Ž&Ž||PinPropagationDelay=0.000000E+000
|RECORD=2|OwnerIndex=99|OwnerPartId=2|FormalType=1|Electrical=4|PinConglomerate=58|PinLength=30|Location.X=810|Location.Y=960|Name=PPS-IN 0-|Designator=7|SwapIDPart=Ž&Ž||PinPropagationDelay=0.000000E+000
|RECORD=2|OwnerIndex=99|OwnerPartId=2|FormalType=1|Electrical=4|PinConglomerate=56|PinLength=30|Location.X=930|Location.Y=900|Name=GND|Designator=8|SwapIDPart=Ž&Ž||PinPropagationDelay=0.000000E+000
|RECORD=2|OwnerIndex=99|OwnerPartId=2|FormalType=1|Electrical=4|PinConglomerate=56|PinLength=30|Location.X=930|Location.Y=890|Name=GND|Designator=9|SwapIDPart=Ž&Ž||PinPropagationDelay=0.000000E+000
|RECORD=2|OwnerIndex=99|OwnerPartId=2|FormalType=1|Electrical=4|PinConglomerate=58|PinLength=30|Location.X=810|Location.Y=940|Name=NC|Designator=10|SwapIDPart=Ž&Ž||PinPropagationDelay=0.000000E+000
|RECORD=2|OwnerIndex=99|OwnerPartId=2|FormalType=1|Electrical=4|PinConglomerate=58|PinLength=30|Location.X=810|Location.Y=930|Name=NC|Designator=11|SwapIDPart=Ž&Ž||PinPropagationDelay=0.000000E+000
|RECORD=2|OwnerIndex=99|OwnerPartId=2|FormalType=1|Electrical=4|PinConglomerate=58|PinLength=30|Location.X=810|Location.Y=920|Name=NC|Designator=12|SwapIDPart=Ž&Ž||PinPropagationDelay=0.000000E+000
|RECORD=2|OwnerIndex=99|OwnerPartId=2|FormalType=1|Electrical=4|PinConglomerate=58|PinLength=30|Location.X=810|Location.Y=910|Name=NC|Designator=13|SwapIDPart=Ž&Ž||PinPropagationDelay=0.000000E+000
|RECORD=2|OwnerIndex=99|OwnerPartId=2|FormalType=1|Electrical=4|PinConglomerate=58|PinLength=30|Location.X=810|Location.Y=900|Name=NC|Designator=14|SwapIDPart=Ž&Ž||PinPropagationDelay=0.000000E+000
|RECORD=2|OwnerIndex=99|OwnerPartId=2|FormalType=1|Electrical=4|PinConglomerate=56|PinLength=30|Location.X=930|Location.Y=880|Name=GND|Designator=15|SwapIDPart=Ž&Ž||PinPropagationDelay=0.000000E+000
|RECORD=2|OwnerIndex=99|OwnerPartId=2|FormalType=1|Electrical=4|PinConglomerate=58|PinLength=30|Location.X=810|Location.Y=890|Name=NC|Designator=16|SwapIDPart=Ž&Ž||PinPropagationDelay=0.000000E+000
|RECORD=2|OwnerIndex=99|OwnerPartId=2|FormalType=1|Electrical=4|PinConglomerate=56|PinLength=30|Location.X=930|Location.Y=950|Name=PPS-OUT +|Designator=17|SwapIDPart=Ž&Ž||PinPropagationDelay=0.000000E+000
|RECORD=2|OwnerIndex=99|OwnerPartId=2|FormalType=1|Electrical=4|PinConglomerate=58|PinLength=30|Location.X=810|Location.Y=880|Name=NC|Designator=18|SwapIDPart=Ž&Ž||PinPropagationDelay=0.000000E+000
|RECORD=2|OwnerIndex=99|OwnerPartId=2|FormalType=1|Electrical=4|PinConglomerate=56|PinLength=30|Location.X=930|Location.Y=940|Name=PPS-OUT -|Designator=19|SwapIDPart=Ž&Ž||PinPropagationDelay=0.000000E+000
|RECORD=2|OwnerIndex=99|OwnerPartId=2|FormalType=1|Electrical=4|PinConglomerate=56|PinLength=30|Location.X=930|Location.Y=920|Name=ALARM|Designator=20|SwapIDPart=Ž&Ž||PinPropagationDelay=0.000000E+000
|RECORD=34|OwnerIndex=99|IndexInSheet=-1|OwnerPartId=-1|Location.X=800|Location.Y=960|Color=8388608|FontID=4|Text=U10|Name=Designator|ReadOnlyState=1
|RECORD=41|OwnerIndex=99|IndexInSheet=-1|OwnerPartId=-1|Location.X=890|Location.Y=900|Color=8388608|FontID=3|IsHidden=T|Text=="MFG PART NUM"|Name=Comment
|RECORD=44|OwnerIndex=99
|RECORD=45|OwnerIndex=177|IndexInSheet=-1|ModelName=SA53|ModelType=PCBLIB|DatafileCount=1|ModelDatafileEntity0=SA53|ModelDatafileKind0=PCBLib|IsCurrent=T|IntegratedModel=T|DatabaseModel=T
|RECORD=46|OwnerIndex=178
|RECORD=48|OwnerIndex=178
|RECORD=1|LibReference=MAC-SA5X|ComponentDescription=MOD, MAC, MAC-SA5X, ATOMIC CLOCK|PartCount=3|DisplayModeCount=1|IndexInSheet=56|OwnerPartId=-1|Location.X=870|Location.Y=800|CurrentPartId=2|LibraryPath=*|SourceLibraryName=Modules.IntLib|TargetFileName=*|AreaColor=11599871|Color=128|PartIDLocked=F|DesignItemId=MAC-SA5X|AllPinCount=28
|RECORD=41|OwnerIndex=181|OwnerPartId=-1|Location.X=870|Location.Y=800|Color=8388608|FontID=3|IsHidden=T|Text=3/22/2006 1:36:44 PM|Name=MODIFY DATE
|RECORD=41|OwnerIndex=181|IndexInSheet=1|OwnerPartId=-1|Location.X=870|Location.Y=800|Color=8388608|FontID=3|IsHidden=T|Text=MAC-SA5X|Name=MFG PART NUM
|RECORD=41|OwnerIndex=181|IndexInSheet=2|OwnerPartId=-1|Location.X=838|Location.Y=832|Color=8388608|FontID=3|IsHidden=T|Text=MOD|Name=CATEGORY
|RECORD=41|OwnerIndex=181|IndexInSheet=3|OwnerPartId=-1|Location.X=838|Location.Y=832|Color=8388608|FontID=3|IsHidden=T|Name=DATE
|RECORD=41|OwnerIndex=181|IndexInSheet=4|OwnerPartId=-1|Location.X=838|Location.Y=832|Color=8388608|FontID=3|IsHidden=T|Text=MICROCHIP|Name=MFG NAME
|RECORD=41|OwnerIndex=181|IndexInSheet=5|OwnerPartId=-1|Location.X=838|Location.Y=832|Color=8388608|FontID=3|IsHidden=T|Text=85C|Name=MAXTEMP
|RECORD=41|OwnerIndex=181|IndexInSheet=6|OwnerPartId=-1|Location.X=838|Location.Y=832|Color=8388608|FontID=3|IsHidden=T|Text=-40C|Name=MINTEMP
|RECORD=41|OwnerIndex=181|IndexInSheet=7|OwnerPartId=-1|Location.X=838|Location.Y=832|Color=8388608|FontID=3|IsHidden=T|Text=AEC-Q200|Name=OTHER
|RECORD=41|OwnerIndex=181|IndexInSheet=8|OwnerPartId=-1|Location.X=838|Location.Y=832|Color=8388608|FontID=3|IsHidden=T|Text=ATOMIC CLOCK|Name=P1
|RECORD=41|OwnerIndex=181|IndexInSheet=9|OwnerPartId=-1|Location.X=838|Location.Y=832|Color=8388608|FontID=3|IsHidden=T|Name=P2
|RECORD=41|OwnerIndex=181|IndexInSheet=10|OwnerPartId=-1|Location.X=838|Location.Y=832|Color=8388608|FontID=3|IsHidden=T|Name=P3
|RECORD=41|OwnerIndex=181|IndexInSheet=11|OwnerPartId=-1|Location.X=838|Location.Y=832|Color=8388608|FontID=3|IsHidden=T|Name=SIZE
|RECORD=41|OwnerIndex=181|IndexInSheet=12|OwnerPartId=-1|Location.X=838|Location.Y=832|Color=8388608|FontID=3|IsHidden=T|Name=SUB
|RECORD=41|OwnerIndex=181|IndexInSheet=13|OwnerPartId=-1|Location.X=838|Location.Y=628|Color=8388608|FontID=1|IsHidden=T|Text=*|Name=SHEETPART
|RECORD=41|OwnerIndex=181|IndexInSheet=14|OwnerPartId=-1|Location.X=838|Location.Y=832|Color=8388608|FontID=1|IsHidden=T|Text=MOD, MAC, MAC-SA5X, ATOMIC CLOCK|Name=DESC
|RECORD=41|OwnerIndex=181|IndexInSheet=15|OwnerPartId=-1|Location.X=828|Location.Y=832|Color=8388608|FontID=1|IsHidden=T|Text=<V PART NUM>|Name=VELENTIUM PART NUM
|RECORD=14|OwnerIndex=181|IsNotAccesible=T|IndexInSheet=16|OwnerPartId=1|Location.X=800|Location.Y=770|Corner.X=950|Corner.Y=820|Color=128|AreaColor=11599871|IsSolid=T
|RECORD=2|OwnerIndex=181|OwnerPartId=1|FormalType=1|Electrical=4|PinConglomerate=58|PinLength=30|Location.X=800|Location.Y=810|Name=FREQ CTRL IN|Designator=P1|SwapIDPart=Ž&Ž||PinPropagationDelay=0.000000E+000
|RECORD=2|OwnerIndex=181|OwnerPartId=1|FormalType=1|Electrical=4|PinConglomerate=58|PinLength=30|Location.X=800|Location.Y=800|Name=GND (CASE)|Designator=P2|SwapIDPart=Ž&Ž||PinPropagationDelay=0.000000E+000
|RECORD=2|OwnerIndex=181|OwnerPartId=1|FormalType=1|Electrical=4|PinConglomerate=58|PinLength=30|Location.X=800|Location.Y=790|Name=RF OUT|Designator=P3|SwapIDPart=Ž&Ž||PinPropagationDelay=0.000000E+000
|RECORD=2|OwnerIndex=181|OwnerPartId=1|FormalType=1|Electrical=4|PinConglomerate=58|PinLength=30|Location.X=800|Location.Y=780|Name=GND (SUPPLY & SIGNAL)|Designator=P4|SwapIDPart=Ž&Ž||PinPropagationDelay=0.000000E+000
|RECORD=2|OwnerIndex=181|OwnerPartId=1|FormalType=1|Electrical=4|PinConglomerate=56|PinLength=30|Location.X=950|Location.Y=780|Name=VCC|Designator=P5|SwapIDPart=Ž&Ž||PinPropagationDelay=0.000000E+000
|RECORD=2|OwnerIndex=181|OwnerPartId=1|FormalType=1|Electrical=4|PinConglomerate=56|PinLength=30|Location.X=950|Location.Y=790|Name=BITE|Designator=P6|SwapIDPart=Ž&Ž||PinPropagationDelay=0.000000E+000
|RECORD=2|OwnerIndex=181|OwnerPartId=1|FormalType=1|Electrical=4|PinConglomerate=56|PinLength=30|Location.X=950|Location.Y=800|Name=RS-232 TX|Designator=P7|SwapIDPart=Ž&Ž||PinPropagationDelay=0.000000E+000
|RECORD=2|OwnerIndex=181|OwnerPartId=1|FormalType=1|Electrical=4|PinConglomerate=56|PinLength=30|Location.X=950|Location.Y=810|Name=RS-232 RX|Designator=P8|SwapIDPart=Ž&Ž||PinPropagationDelay=0.000000E+000
|RECORD=41|OwnerIndex=181|IndexInSheet=25|OwnerPartId=-1|Location.X=810|Location.Y=718|Color=8388608|FontID=3|Text=RV-3049-C3|Name=VALUE
|RECORD=14|OwnerIndex=181|IsNotAccesible=T|IndexInSheet=26|OwnerPartId=2|Location.X=810|Location.Y=730|Corner.X=930|Corner.Y=860|Color=128|AreaColor=11599871|IsSolid=T
|RECORD=2|OwnerIndex=181|OwnerPartId=2|FormalType=1|Electrical=4|PinConglomerate=58|PinLength=30|Location.X=810|Location.Y=850|Name=PPS-IN 1+|Designator=1|SwapIDPart=Ž&Ž||PinPropagationDelay=0.000000E+000
|RECORD=2|OwnerIndex=181|OwnerPartId=2|FormalType=1|Electrical=4|PinConglomerate=56|PinLength=30|Location.X=930|Location.Y=850|Name=USB DATA +|Designator=2|SwapIDPart=Ž&Ž||PinPropagationDelay=0.000000E+000
|RECORD=2|OwnerIndex=181|OwnerPartId=2|FormalType=1|Electrical=4|PinConglomerate=58|PinLength=30|Location.X=810|Location.Y=840|Name=PPS-IN 1-|Designator=3|SwapIDPart=Ž&Ž||PinPropagationDelay=0.000000E+000
|RECORD=2|OwnerIndex=181|OwnerPartId=2|FormalType=1|Electrical=4|PinConglomerate=56|PinLength=30|Location.X=930|Location.Y=840|Name=USB DATA -|Designator=4|SwapIDPart=Ž&Ž||PinPropagationDelay=0.000000E+000
|RECORD=2|OwnerIndex=181|OwnerPartId=2|FormalType=1|Electrical=4|PinConglomerate=58|PinLength=30|Location.X=810|Location.Y=830|Name=PPS-IN 0+|Designator=5|SwapIDPart=Ž&Ž||PinPropagationDelay=0.000000E+000
|RECORD=2|OwnerIndex=181|OwnerPartId=2|FormalType=1|Electrical=4|PinConglomerate=56|PinLength=30|Location.X=930|Location.Y=830|Name=USB POWER|Designator=6|SwapIDPart=Ž&Ž||PinPropagationDelay=0.000000E+000
|RECORD=2|OwnerIndex=181|OwnerPartId=2|FormalType=1|Electrical=4|PinConglomerate=58|PinLength=30|Location.X=810|Location.Y=820|Name=PPS-IN 0-|Designator=7|SwapIDPart=Ž&Ž||PinPropagationDelay=0.000000E+000
|RECORD=2|OwnerIndex=181|OwnerPartId=2|FormalType=1|Electrical=4|PinConglomerate=56|PinLength=30|Location.X=930|Location.Y=760|Name=GND|Designator=8|SwapIDPart=Ž&Ž||PinPropagationDelay=0.000000E+000
|RECORD=2|OwnerIndex=181|OwnerPartId=2|FormalType=1|Electrical=4|PinConglomerate=56|PinLength=30|Location.X=930|Location.Y=750|Name=GND|Designator=9|SwapIDPart=Ž&Ž||PinPropagationDelay=0.000000E+000
|RECORD=2|OwnerIndex=181|OwnerPartId=2|FormalType=1|Electrical=4|PinConglomerate=58|PinLength=30|Location.X=810|Location.Y=800|Name=NC|Designator=10|SwapIDPart=Ž&Ž||PinPropagationDelay=0.000000E+000
|RECORD=2|OwnerIndex=181|OwnerPartId=2|FormalType=1|Electrical=4|PinConglomerate=58|PinLength=30|Location.X=810|Location.Y=790|Name=NC|Designator=11|SwapIDPart=Ž&Ž||PinPropagationDelay=0.000000E+000
|RECORD=2|OwnerIndex=181|OwnerPartId=2|FormalType=1|Electrical=4|PinConglomerate=58|PinLength=30|Location.X=810|Location.Y=780|Name=NC|Designator=12|SwapIDPart=Ž&Ž||PinPropagationDelay=0.000000E+000
|RECORD=2|OwnerIndex=181|OwnerPartId=2|FormalType=1|Electrical=4|PinConglomerate=58|PinLength=30|Location.X=810|Location.Y=770|Name=NC|Designator=13|SwapIDPart=Ž&Ž||PinPropagationDelay=0.000000E+000
|RECORD=2|OwnerIndex=181|OwnerPartId=2|FormalType=1|Electrical=4|PinConglomerate=58|PinLength=30|Location.X=810|Location.Y=760|Name=NC|Designator=14|SwapIDPart=Ž&Ž||PinPropagationDelay=0.000000E+000
|RECORD=2|OwnerIndex=181|OwnerPartId=2|FormalType=1|Electrical=4|PinConglomerate=56|PinLength=30|Location.X=930|Location.Y=740|Name=GND|Designator=15|SwapIDPart=Ž&Ž||PinPropagationDelay=0.000000E+000
|RECORD=2|OwnerIndex=181|OwnerPartId=2|FormalType=1|Electrical=4|PinConglomerate=58|PinLength=30|Location.X=810|Location.Y=750|Name=NC|Designator=16|SwapIDPart=Ž&Ž||PinPropagationDelay=0.000000E+000
|RECORD=2|OwnerIndex=181|OwnerPartId=2|FormalType=1|Electrical=4|PinConglomerate=56|PinLength=30|Location.X=930|Location.Y=810|Name=PPS-OUT +|Designator=17|SwapIDPart=Ž&Ž||PinPropagationDelay=0.000000E+000
|RECORD=2|OwnerIndex=181|OwnerPartId=2|FormalType=1|Electrical=4|PinConglomerate=58|PinLength=30|Location.X=810|Location.Y=740|Name=NC|Designator=18|SwapIDPart=Ž&Ž||PinPropagationDelay=0.000000E+000
|RECORD=2|OwnerIndex=181|OwnerPartId=2|FormalType=1|Electrical=4|PinConglomerate=56|PinLength=30|Location.X=930|Location.Y=800|Name=PPS-OUT -|Designator=19|SwapIDPart=Ž&Ž||PinPropagationDelay=0.000000E+000
|RECORD=2|OwnerIndex=181|OwnerPartId=2|FormalType=1|Electrical=4|PinConglomerate=56|PinLength=30|Location.X=930|Location.Y=780|Name=ALARM|Designator=20|SwapIDPart=Ž&Ž||PinPropagationDelay=0.000000E+000
|RECORD=34|OwnerIndex=181|IndexInSheet=-1|OwnerPartId=-1|Location.X=810|Location.Y=860|Color=8388608|FontID=4|Text=U10|Name=Designator|ReadOnlyState=1
|RECORD=41|OwnerIndex=181|IndexInSheet=-1|OwnerPartId=-1|Location.X=890|Location.Y=760|Color=8388608|FontID=3|IsHidden=T|Text=="MFG PART NUM"|Name=Comment
|RECORD=44|OwnerIndex=181
|RECORD=45|OwnerIndex=259|IndexInSheet=-1|ModelName=SA53|ModelType=PCBLIB|DatafileCount=1|ModelDatafileEntity0=SA53|ModelDatafileKind0=PCBLib|IsCurrent=T|IntegratedModel=T|DatabaseModel=T
|RECORD=46|OwnerIndex=260
|RECORD=48|OwnerIndex=260
|RECORD=1|LibReference=CAP|ComponentDescription=C0603X104K5RACAUTO|PartCount=2|DisplayModeCount=2|IndexInSheet=57|OwnerPartId=-1|Location.X=1140|Location.Y=890|Orientation=1|CurrentPartId=1|SourceLibraryName=Altium Content Vault|TargetFileName=*|AreaColor=11599871|Color=128|PartIDLocked=F|DesignItemId=CMP-2006-00003-1|AllPinCount=2
|RECORD=2|OwnerIndex=263|OwnerPartId=1|OwnerPartDisplayMode=1|FormalType=1|Electrical=4|PinConglomerate=35|PinLength=10|Location.X=1150|Location.Y=890|Name=1|Designator=1|PinPropagationDelay=0.000000E+000
|RECORD=2|OwnerIndex=263|OwnerPartId=1|OwnerPartDisplayMode=1|FormalType=1|Electrical=4|PinConglomerate=33|PinLength=10|Location.X=1150|Location.Y=900|Name=2|Designator=2|PinPropagationDelay=0.000000E+000
|RECORD=13|OwnerIndex=263|IsNotAccesible=T|IndexInSheet=2|OwnerPartId=1|OwnerPartDisplayMode=1|Location.X=1158|Location.Y=890|Corner.X=1142|Corner.Y=890|LineWidth=1|Color=16711680
|RECORD=13|OwnerIndex=263|IsNotAccesible=T|IndexInSheet=3|OwnerPartId=1|OwnerPartDisplayMode=1|Location.X=1150|Location.Y=894|Corner.X=1150|Corner.Y=900|LineWidth=1|Color=16711680
|RECORD=12|OwnerIndex=263|IsNotAccesible=T|IndexInSheet=4|OwnerPartId=1|OwnerPartDisplayMode=1|Location.X=1150|Location.Y=910|Radius=16|LineWidth=1|StartAngle=241.000|EndAngle=270.000|Color=16711680
|RECORD=12|OwnerIndex=263|IsNotAccesible=T|IndexInSheet=5|OwnerPartId=1|OwnerPartDisplayMode=1|Location.X=1150|Location.Y=910|Radius=16|LineWidth=1|StartAngle=270.000|EndAngle=299.000|Color=16711680
|RECORD=2|OwnerIndex=263|OwnerPartId=1|FormalType=1|Electrical=4|PinConglomerate=35|PinLength=10|Location.X=1150|Location.Y=890|Name=1|Designator=1|PinPropagationDelay=0.000000E+000
|RECORD=2|OwnerIndex=263|OwnerPartId=1|FormalType=1|Electrical=4|PinConglomerate=33|PinLength=10|Location.X=1150|Location.Y=900|Name=2|Designator=2|PinPropagationDelay=0.000000E+000
|RECORD=13|OwnerIndex=263|IsNotAccesible=T|IndexInSheet=8|OwnerPartId=1|Location.X=1142|Location.Y=897|Corner.X=1158|Corner.Y=897|LineWidth=1|Color=16711680
|RECORD=13|OwnerIndex=263|IsNotAccesible=T|IndexInSheet=9|OwnerPartId=1|Location.X=1158|Location.Y=893|Corner.X=1142|Corner.Y=893|LineWidth=1|Color=16711680
|RECORD=6|OwnerIndex=263|IsNotAccesible=T|IndexInSheet=10|OwnerPartId=1|LineWidth=1|Color=16711680|LocationCount=2|X1=1150|Y1=890|X2=1150|Y2=893
|RECORD=6|OwnerIndex=263|IsNotAccesible=T|IndexInSheet=11|OwnerPartId=1|LineWidth=1|Color=16711680|LocationCount=2|X1=1150|Y1=900|X2=1150|Y2=897
|RECORD=41|OwnerIndex=263|IndexInSheet=12|OwnerPartId=-1|Location.X=1141|Location.Y=912|Color=8388608|FontID=1|IsHidden=T|Text=Kemet|Name=Manufacturer
|RECORD=41|OwnerIndex=263|IndexInSheet=13|OwnerPartId=-1|Location.X=1141|Location.Y=912|Color=8388608|FontID=1|IsHidden=T|Text=C0603X104K5RACAUTO|Name=Part Number
|RECORD=34|OwnerIndex=263|IndexInSheet=-1|OwnerPartId=-1|Location.X=1159|Location.Y=891|Color=8388608|FontID=4|Text=C63|Name=Designator|ReadOnlyState=1
|RECORD=41|OwnerIndex=263|IndexInSheet=-1|OwnerPartId=-1|Location.X=1159|Location.Y=881|Color=8388608|FontID=4|Text=0.1uF|Name=Comment
|RECORD=44|OwnerIndex=263
|RECORD=45|OwnerIndex=284|IndexInSheet=-1|Description=Chip Capacitor, 2-Leads, Body 1.60x0.80mm, IPC Low Density|UseComponentLibrary=T|ModelName=CAPC1608X87X45ML20T05|ModelType=PCBLIB|DatafileCount=1|ModelDatafileEntity0=CAPC1608X87X45ML20T05|ModelDatafileKind0=PCBLib|IsCurrent=T|DatalinksLocked=T|DatabaseDatalinksLocked=T
|RECORD=46|OwnerIndex=285
|RECORD=48|OwnerIndex=285
|RECORD=41|OwnerIndex=287|IndexInSheet=-1|OwnerPartId=-1|Color=8388608|FontID=1|Text=2D|Name=Available Preview Images
|RECORD=45|OwnerIndex=284|IndexInSheet=-1|Description=Chip Capacitor, 2-Leads, Body 1.60x0.80mm, IPC High Density|UseComponentLibrary=T|ModelName=CAPC1608X87X45LL20T05|ModelType=PCBLIB|DatafileCount=1|ModelDatafileEntity0=CAPC1608X87X45LL20T05|ModelDatafileKind0=PCBLib|DatalinksLocked=T|DatabaseDatalinksLocked=T
|RECORD=46|OwnerIndex=289
|RECORD=48|OwnerIndex=289
|RECORD=41|OwnerIndex=291|IndexInSheet=-1|OwnerPartId=-1|Color=8388608|FontID=1|Text=2D|Name=Available Preview Images
|RECORD=45|OwnerIndex=284|IndexInSheet=-1|Description=Chip Capacitor, 2-Leads, Body 1.60x0.80mm, IPC Medium Density|UseComponentLibrary=T|ModelName=CAPC1608X87X45NL20T05|ModelType=PCBLIB|DatafileCount=1|ModelDatafileEntity0=CAPC1608X87X45NL20T05|ModelDatafileKind0=PCBLib|DatalinksLocked=T|DatabaseDatalinksLocked=T
|RECORD=46|OwnerIndex=293
|RECORD=48|OwnerIndex=293
|RECORD=41|OwnerIndex=295|IndexInSheet=-1|OwnerPartId=-1|Color=8388608|FontID=1|Text=2D|Name=Available Preview Images
|RECORD=41|IndexInSheet=58|OwnerPartId=-1|Color=8388608|FontID=1|IsHidden=T|Name=ConfigurationParameters|ReadOnlyState=1
|RECORD=41|IndexInSheet=59|OwnerPartId=-1|Color=8388608|FontID=1|IsHidden=T|Name=ConfiguratorName|ReadOnlyState=1
|RECORD=41|IndexInSheet=60|OwnerPartId=-1|Color=8388608|FontID=1|IsHidden=T|Name=VersionControl_RevNumber|ReadOnlyState=1
|RECORD=41|IndexInSheet=61|OwnerPartId=-1|Color=8388608|FontID=1|IsHidden=T|Name=IsUserConfigurable|ReadOnlyState=1
|RECORD=41|IndexInSheet=62|OwnerPartId=-1|Color=8388608|FontID=1|IsHidden=T|Name=VersionControl_ProjFolderRevNumber|ReadOnlyState=1
|RECORD=41|IndexInSheet=63|OwnerPartId=-1|Color=8388608|FontID=1|IsHidden=T|Name=SPICEModelCache|ReadOnlyState=1
|RECORD=1|LibReference=IN-LNDRV-DS90LV027AHM|ComponentDescription=Automotive LVDS Dual Differential Driver, 8-pin Narrow SOIC|PartCount=2|DisplayModeCount=1|IndexInSheet=64|OwnerPartId=-1|Location.X=860|Location.Y=610|CurrentPartId=1|LibraryPath=*|SourceLibraryName=Altium Content Vault|TargetFileName=*|AreaColor=11599871|Color=128|PartIDLocked=T|DesignItemId=CMP-0058-01000-2|AllPinCount=8
|RECORD=14|OwnerIndex=303|IsNotAccesible=T|OwnerPartId=1|Location.X=860|Location.Y=530|Corner.X=930|Corner.Y=610|Color=128|AreaColor=11599871|IsSolid=T
|RECORD=2|OwnerIndex=303|OwnerPartId=1|FormalType=1|PinConglomerate=58|PinLength=20|Location.X=860|Location.Y=600|Name=DI1|Designator=2|SwapIDPart=Ž&Ž||PinPropagationDelay=0.000000E+000
|RECORD=2|OwnerIndex=303|OwnerPartId=1|FormalType=1|PinConglomerate=58|PinLength=20|Location.X=860|Location.Y=570|Name=DI2|Designator=3|SwapIDPart=Ž&Ž||PinPropagationDelay=0.000000E+000
|RECORD=2|OwnerIndex=303|OwnerPartId=1|FormalType=1|Electrical=2|PinConglomerate=56|PinLength=20|Location.X=930|Location.Y=600|Name=DO+1|Designator=7|SwapIDPart=Ž&Ž||PinPropagationDelay=0.000000E+000
|RECORD=2|OwnerIndex=303|OwnerPartId=1|FormalType=1|Electrical=2|PinConglomerate=56|PinLength=20|Location.X=930|Location.Y=570|Name=DO+2|Designator=6|SwapIDPart=Ž&Ž||PinPropagationDelay=0.000000E+000
|RECORD=2|OwnerIndex=303|OwnerPartId=1|FormalType=1|Electrical=2|PinConglomerate=56|PinLength=20|Location.X=930|Location.Y=590|Name=DO-1|Designator=8|SwapIDPart=Ž&Ž||PinPropagationDelay=0.000000E+000
|RECORD=2|OwnerIndex=303|OwnerPartId=1|FormalType=1|Electrical=2|PinConglomerate=56|PinLength=20|Location.X=930|Location.Y=560|Name=DO-2|Designator=5|SwapIDPart=Ž&Ž||PinPropagationDelay=0.000000E+000
|RECORD=2|OwnerIndex=303|OwnerPartId=1|FormalType=1|Electrical=7|PinConglomerate=56|PinLength=20|Location.X=930|Location.Y=540|Name=GND|Designator=4|SwapIDPart=Ž&Ž||PinPropagationDelay=0.000000E+000
|RECORD=2|OwnerIndex=303|OwnerPartId=1|FormalType=1|Electrical=7|PinConglomerate=58|PinLength=20|Location.X=860|Location.Y=540|Name=VCC|Designator=1|SwapIDPart=Ž&Ž||PinPropagationDelay=0.000000E+000
|RECORD=41|OwnerIndex=303|IndexInSheet=9|OwnerPartId=-1|Location.X=838|Location.Y=610|Color=8388608|FontID=1|IsHidden=T|Text=Oct-2008|Name=DatasheetVersion
|RECORD=41|OwnerIndex=303|IndexInSheet=10|OwnerPartId=-1|Location.X=838|Location.Y=610|Color=8388608|FontID=1|IsHidden=T|Text=8|Name=PinCount
|RECORD=41|OwnerIndex=303|IndexInSheet=11|OwnerPartId=-1|Location.X=838|Location.Y=610|Color=8388608|FontID=1|IsHidden=T|Text=Component URLs added|Name=RevisionNote
|RECORD=41|OwnerIndex=303|IndexInSheet=12|OwnerPartId=-1|Location.X=838|Location.Y=610|Color=8388608|FontID=1|IsHidden=T|Text=SOIC127P600-8|Name=Code_IPC
|RECORD=41|OwnerIndex=303|IndexInSheet=13|OwnerPartId=-1|Location.X=838|Location.Y=610|Color=8388608|FontID=1|IsHidden=T|Text=National Semiconductor|Name=Manufacturer
|RECORD=41|OwnerIndex=303|IndexInSheet=14|OwnerPartId=-1|Location.X=838|Location.Y=610|Color=8388608|FontID=1|IsHidden=T|Text=NSZXTT*90LV0*27AQM|Name=PackageTopMarking
|RECORD=41|OwnerIndex=303|IndexInSheet=15|OwnerPartId=-1|Location.X=838|Location.Y=610|Color=8388608|FontID=1|IsHidden=T|Text=Interface IC|Name=CompType
|RECORD=41|OwnerIndex=303|IndexInSheet=16|OwnerPartId=-1|Location.X=838|Location.Y=610|Color=8388608|FontID=2|IsHidden=T|Text=http://www.national.com/ds/DS/DS90LV027AQ.pdf|Name=ComponentLink1URL
|RECORD=41|OwnerIndex=303|IndexInSheet=17|OwnerPartId=-1|Location.X=838|Location.Y=610|Color=8388608|FontID=1|IsHidden=T|Text=M08A Package Page|Name=ComponentLink3Description
|RECORD=41|OwnerIndex=303|IndexInSheet=18|OwnerPartId=-1|Location.X=838|Location.Y=610|Color=8388608|FontID=1|IsHidden=T|Text=SOIC Narrow, 4.9 x 3.9 x 1.45mm, 8 Lead, 1.27mm Pitch|Name=PackageDescription
|RECORD=41|OwnerIndex=303|IndexInSheet=19|OwnerPartId=-1|Location.X=838|Location.Y=610|Color=8388608|FontID=1|IsHidden=T|Text=DS90LV027AQ Web Page|Name=ComponentLink2Description
|RECORD=41|OwnerIndex=303|IndexInSheet=20|OwnerPartId=-1|Location.X=838|Location.Y=610|Color=8388608|FontID=2|IsHidden=T|Text=http://www.national.com/pf/DS/DS90LV027AQ.html|Name=ComponentLink2URL
|RECORD=41|OwnerIndex=303|IndexInSheet=21|OwnerPartId=-1|Location.X=838|Location.Y=610|Color=8388608|FontID=1|IsHidden=T|Text=Y|Name=RoHS
|RECORD=41|OwnerIndex=303|IndexInSheet=22|OwnerPartId=-1|Location.X=838|Location.Y=610|Color=8388608|FontID=1|IsHidden=T|Text=N|Name=PowerWise
|RECORD=41|OwnerIndex=303|IndexInSheet=23|OwnerPartId=-1|Location.X=838|Location.Y=610|Color=8388608|FontID=1|IsHidden=T|Text=MS-012-AA|Name=Code_JEDEC
|RECORD=41|OwnerIndex=303|IndexInSheet=24|OwnerPartId=-1|Location.X=838|Location.Y=610|Color=8388608|FontID=1|IsHidden=T|Text=M08A|Name=PackageReference
|RECORD=41|OwnerIndex=303|IndexInSheet=25|OwnerPartId=-1|Location.X=838|Location.Y=610|Color=8388608|FontID=1|IsHidden=T|Text=revM, May-2009|Name=PackageVersion
|RECORD=41|OwnerIndex=303|IndexInSheet=26|OwnerPartId=-1|Location.X=838|Location.Y=610|Color=8388608|FontID=1|IsHidden=T|Text=DS90LV027AQ Datasheet|Name=ComponentLink1Description
|RECORD=41|OwnerIndex=303|IndexInSheet=27|OwnerPartId=-1|Location.X=838|Location.Y=610|Color=8388608|FontID=2|IsHidden=T|Text=http://www.national.com/packaging/folders/m08a.html|Name=ComponentLink3URL
|RECORD=34|OwnerIndex=303|IndexInSheet=-1|OwnerPartId=-1|Location.X=860|Location.Y=610|Color=8388608|FontID=1|Text=U3|Name=Designator|ReadOnlyState=1
|RECORD=41|OwnerIndex=303|IndexInSheet=-1|OwnerPartId=-1|Location.X=860|Location.Y=520|Color=8388608|FontID=1|Text=DS90LV027AQMA|Name=Comment
|RECORD=44|OwnerIndex=303
|RECORD=45|OwnerIndex=342|IndexInSheet=-1|Description=SOIC, 8-Leads, Body 4.9x3.9mm, Pitch 1.27mm, IPC Medium Density|UseComponentLibrary=T|ModelName=M08A_N|ModelType=PCBLIB|DatafileCount=1|ModelDatafileEntity0=M08A_N|ModelDatafileKind0=PCBLib|IsCurrent=T|DatalinksLocked=T|DatabaseDatalinksLocked=T
|RECORD=46|OwnerIndex=343
|RECORD=48|OwnerIndex=343
|RECORD=41|OwnerIndex=345|IndexInSheet=-1|OwnerPartId=-1|Color=8388608|FontID=1|IsHidden=T|Text=2D|Name=Available Preview Images
|RECORD=45|OwnerIndex=342|IndexInSheet=-1|Description=SOIC, 8-Leads, Body 4.9x3.9mm, Pitch 1.27mm, IPC Low Density|UseComponentLibrary=T|ModelName=M08A_M|ModelType=PCBLIB|DatafileCount=1|ModelDatafileEntity0=M08A_M|ModelDatafileKind0=PCBLib|DatalinksLocked=T|DatabaseDatalinksLocked=T
|RECORD=46|OwnerIndex=347
|RECORD=48|OwnerIndex=347
|RECORD=41|OwnerIndex=349|IndexInSheet=-1|OwnerPartId=-1|Color=8388608|FontID=1|IsHidden=T|Text=2D|Name=Available Preview Images
|RECORD=45|OwnerIndex=342|IndexInSheet=-1|Description=SOIC, 8-Leads, Body 4.9x3.9mm, Pitch 1.27mm, IPC High Density|UseComponentLibrary=T|ModelName=M08A_L|ModelType=PCBLIB|DatafileCount=1|ModelDatafileEntity0=M08A_L|ModelDatafileKind0=PCBLib|DatalinksLocked=T|DatabaseDatalinksLocked=T
|RECORD=46|OwnerIndex=351
|RECORD=48|OwnerIndex=351
|RECORD=41|OwnerIndex=353|IndexInSheet=-1|OwnerPartId=-1|Color=8388608|FontID=1|IsHidden=T|Text=2D|Name=Available Preview Images
|RECORD=1|LibReference=IN-LNRX-DS90LV028AHM|ComponentDescription=Automotive LVDS Dual Differential Line Receiver, 8-pin Narrow SOIC|PartCount=2|DisplayModeCount=1|IndexInSheet=65|OwnerPartId=-1|Location.X=830|Location.Y=340|CurrentPartId=1|LibraryPath=*|SourceLibraryName=Altium Content Vault|TargetFileName=*|AreaColor=11599871|Color=128|PartIDLocked=T|DesignItemId=CMP-0058-01010-2|AllPinCount=8
|RECORD=14|OwnerIndex=355|IsNotAccesible=T|OwnerPartId=1|Location.X=830|Location.Y=260|Corner.X=910|Corner.Y=340|Color=128|AreaColor=11599871|IsSolid=T
|RECORD=2|OwnerIndex=355|OwnerPartId=1|FormalType=1|PinConglomerate=58|PinLength=20|Location.X=830|Location.Y=320|Name=RIN1-|Designator=1|SwapIDPart=Ž&Ž||PinPropagationDelay=0.000000E+000
|RECORD=2|OwnerIndex=355|OwnerPartId=1|FormalType=1|PinConglomerate=58|PinLength=20|Location.X=830|Location.Y=330|Name=RIN1+|Designator=2|SwapIDPart=Ž&Ž||PinPropagationDelay=0.000000E+000
|RECORD=2|OwnerIndex=355|OwnerPartId=1|FormalType=1|PinConglomerate=58|PinLength=20|Location.X=830|Location.Y=300|Name=RIN2+|Designator=3|SwapIDPart=Ž&Ž||PinPropagationDelay=0.000000E+000
|RECORD=2|OwnerIndex=355|OwnerPartId=1|FormalType=1|PinConglomerate=58|PinLength=20|Location.X=830|Location.Y=290|Name=RIN2-|Designator=4|SwapIDPart=Ž&Ž||PinPropagationDelay=0.000000E+000
|RECORD=2|OwnerIndex=355|OwnerPartId=1|FormalType=1|Electrical=7|PinConglomerate=56|PinLength=20|Location.X=910|Location.Y=270|Name=GND|Designator=5|SwapIDPart=Ž&Ž||PinPropagationDelay=0.000000E+000
|RECORD=2|OwnerIndex=355|OwnerPartId=1|FormalType=1|Electrical=2|PinConglomerate=56|PinLength=20|Location.X=910|Location.Y=300|Name=ROUT2|Designator=6|SwapIDPart=Ž&Ž||PinPropagationDelay=0.000000E+000
|RECORD=2|OwnerIndex=355|OwnerPartId=1|FormalType=1|Electrical=2|PinConglomerate=56|PinLength=20|Location.X=910|Location.Y=330|Name=ROUT1|Designator=7|SwapIDPart=Ž&Ž||PinPropagationDelay=0.000000E+000
|RECORD=2|OwnerIndex=355|OwnerPartId=1|FormalType=1|Electrical=7|PinConglomerate=58|PinLength=20|Location.X=830|Location.Y=270|Name=VCC|Designator=8|SwapIDPart=Ž&Ž||PinPropagationDelay=0.000000E+000
|RECORD=41|OwnerIndex=355|IndexInSheet=9|OwnerPartId=-1|Location.X=808|Location.Y=340|Color=8388608|FontID=1|IsHidden=T|Text=National Semiconductor|Name=Manufacturer
|RECORD=41|OwnerIndex=355|IndexInSheet=10|OwnerPartId=-1|Location.X=808|Location.Y=340|Color=8388608|FontID=1|IsHidden=T|Text=Oct-2008|Name=DatasheetVersion
|RECORD=41|OwnerIndex=355|IndexInSheet=11|OwnerPartId=-1|Location.X=808|Location.Y=340|Color=8388608|FontID=1|IsHidden=T|Text=N|Name=PowerWise
|RECORD=41|OwnerIndex=355|IndexInSheet=12|OwnerPartId=-1|Location.X=808|Location.Y=340|Color=8388608|FontID=1|IsHidden=T|Text=M08A|Name=PackageReference
|RECORD=41|OwnerIndex=355|IndexInSheet=13|OwnerPartId=-1|Location.X=808|Location.Y=340|Color=8388608|FontID=1|IsHidden=T|Text=Component URLs added|Name=RevisionNote
|RECORD=41|OwnerIndex=355|IndexInSheet=14|OwnerPartId=-1|Location.X=808|Location.Y=340|Color=8388608|FontID=1|IsHidden=T|Text=MS-012-AA|Name=Code_JEDEC
|RECORD=41|OwnerIndex=355|IndexInSheet=15|OwnerPartId=-1|Location.X=808|Location.Y=340|Color=8388608|FontID=1|IsHidden=T|Text=revM, May-2009|Name=PackageVersion
|RECORD=41|OwnerIndex=355|IndexInSheet=16|OwnerPartId=-1|Location.X=808|Location.Y=340|Color=8388608|FontID=2|IsHidden=T|Text=http://www.national.com/ds/DS/DS90LV028AQ.pdf|Name=ComponentLink1URL
|RECORD=41|OwnerIndex=355|IndexInSheet=17|OwnerPartId=-1|Location.X=808|Location.Y=340|Color=8388608|FontID=1|IsHidden=T|Text=8|Name=PinCount
|RECORD=41|OwnerIndex=355|IndexInSheet=18|OwnerPartId=-1|Location.X=808|Location.Y=340|Color=8388608|FontID=1|IsHidden=T|Text=M08A Package Page|Name=ComponentLink3Description
|RECORD=41|OwnerIndex=355|IndexInSheet=19|OwnerPartId=-1|Location.X=808|Location.Y=340|Color=8388608|FontID=1|IsHidden=T|Text=DS90LV028AQ Datasheet|Name=ComponentLink1Description
|RECORD=41|OwnerIndex=355|IndexInSheet=20|OwnerPartId=-1|Location.X=808|Location.Y=340|Color=8388608|FontID=1|IsHidden=T|Text=SOIC127P600-8|Name=Code_IPC
|RECORD=41|OwnerIndex=355|IndexInSheet=21|OwnerPartId=-1|Location.X=808|Location.Y=340|Color=8388608|FontID=1|IsHidden=T|Text=Y|Name=RoHS
|RECORD=41|OwnerIndex=355|IndexInSheet=22|OwnerPartId=-1|Location.X=808|Location.Y=340|Color=8388608|FontID=2|IsHidden=T|Text=http://www.national.com/pf/DS/DS90LV028AQ.html|Name=ComponentLink2URL
|RECORD=41|OwnerIndex=355|IndexInSheet=23|OwnerPartId=-1|Location.X=808|Location.Y=340|Color=8388608|FontID=1|IsHidden=T|Text=NSZXTT*90LV0*28AQM|Name=PackageTopMarking
|RECORD=41|OwnerIndex=355|IndexInSheet=24|OwnerPartId=-1|Location.X=808|Location.Y=340|Color=8388608|FontID=1|IsHidden=T|Text=SOIC Narrow, 4.9 x 3.9 x 1.45mm, 8 Lead, 1.27mm Pitch|Name=PackageDescription
|RECORD=41|OwnerIndex=355|IndexInSheet=25|OwnerPartId=-1|Location.X=808|Location.Y=340|Color=8388608|FontID=1|IsHidden=T|Text=DS90LV028AQ Web Page|Name=ComponentLink2Description
|RECORD=41|OwnerIndex=355|IndexInSheet=26|OwnerPartId=-1|Location.X=808|Location.Y=340|Color=8388608|FontID=2|IsHidden=T|Text=http://www.national.com/packaging/folders/m08a.html|Name=ComponentLink3URL
|RECORD=41|OwnerIndex=355|IndexInSheet=27|OwnerPartId=-1|Location.X=808|Location.Y=340|Color=8388608|FontID=1|IsHidden=T|Text=Interface IC|Name=CompType
|RECORD=34|OwnerIndex=355|IndexInSheet=-1|OwnerPartId=-1|Location.X=830|Location.Y=340|Color=8388608|FontID=1|Text=U4|Name=Designator|ReadOnlyState=1
|RECORD=41|OwnerIndex=355|IndexInSheet=-1|OwnerPartId=-1|Location.X=830|Location.Y=250|Color=8388608|FontID=1|Text=DS90LV028AQMA|Name=Comment
|RECORD=44|OwnerIndex=355
|RECORD=45|OwnerIndex=394|IndexInSheet=-1|Description=SOIC, 8-Leads, Body 4.9x3.9mm, Pitch 1.27mm, IPC High Density|UseComponentLibrary=T|ModelName=M08A_L|ModelType=PCBLIB|DatafileCount=1|ModelDatafileEntity0=M08A_L|ModelDatafileKind0=PCBLib|IsCurrent=T|DatalinksLocked=T|DatabaseDatalinksLocked=T
|RECORD=46|OwnerIndex=395
|RECORD=48|OwnerIndex=395
|RECORD=41|OwnerIndex=397|IndexInSheet=-1|OwnerPartId=-1|Color=8388608|FontID=1|IsHidden=T|Text=2D|Name=Available Preview Images
|RECORD=45|OwnerIndex=394|IndexInSheet=-1|Description=SOIC, 8-Leads, Body 4.9x3.9mm, Pitch 1.27mm, IPC Low Density|UseComponentLibrary=T|ModelName=M08A_M|ModelType=PCBLIB|DatafileCount=1|ModelDatafileEntity0=M08A_M|ModelDatafileKind0=PCBLib|DatalinksLocked=T|DatabaseDatalinksLocked=T
|RECORD=46|OwnerIndex=399
|RECORD=48|OwnerIndex=399
|RECORD=41|OwnerIndex=401|IndexInSheet=-1|OwnerPartId=-1|Color=8388608|FontID=1|IsHidden=T|Text=2D|Name=Available Preview Images
|RECORD=45|OwnerIndex=394|IndexInSheet=-1|Description=SOIC, 8-Leads, Body 4.9x3.9mm, Pitch 1.27mm, IPC Medium Density|UseComponentLibrary=T|ModelName=M08A_N|ModelType=PCBLIB|DatafileCount=1|ModelDatafileEntity0=M08A_N|ModelDatafileKind0=PCBLib|DatalinksLocked=T|DatabaseDatalinksLocked=T
|RECORD=46|OwnerIndex=403
|RECORD=48|OwnerIndex=403
|RECORD=41|OwnerIndex=405|IndexInSheet=-1|OwnerPartId=-1|Color=8388608|FontID=1|IsHidden=T|Text=2D|Name=Available Preview Images
|RECORD=1|LibReference=RES-2|ComponentDescription=Chip Resistor, 4.7 KOhm, +/- 1%, 0.1 W, -55 to 155 degC, 0603 (1608 Metric), RoHS, Tape and Reel RC0603FR-074K7L|PartCount=2|DisplayModeCount=1|IndexInSheet=66|OwnerPartId=-1|Location.X=770|Location.Y=510|Orientation=1|CurrentPartId=1|LibraryPath=*|SourceLibraryName=Altium Content Vault|TargetFileName=*|AreaColor=11599871|Color=128|PartIDLocked=T|DesignItemId=CMP-2000-06942-1|AllPinCount=2
|RECORD=2|OwnerIndex=407|OwnerPartId=1|FormalType=1|Electrical=4|PinConglomerate=33|PinLength=10|Location.X=770|Location.Y=530|Name=2|Designator=2|PinPropagationDelay=0.000000E+000
|RECORD=2|OwnerIndex=407|OwnerPartId=1|FormalType=1|Electrical=4|PinConglomerate=35|PinLength=10|Location.X=770|Location.Y=510|Name=1|Designator=1|PinPropagationDelay=0.000000E+000
|RECORD=6|OwnerIndex=407|IsNotAccesible=T|IndexInSheet=2|OwnerPartId=1|LineWidth=1|Color=16711680|LocationCount=10|X1=770|Y1=530|X2=770|Y2=526|X3=772|Y3=525|X4=768|Y4=523|X5=772|Y5=521|X6=768|Y6=519|X7=772|Y7=517|X8=768|Y8=515|X9=770|Y9=514|X10=770|Y10=510
|RECORD=41|OwnerIndex=407|IndexInSheet=3|OwnerPartId=-1|Location.X=767|Location.Y=542|Color=8388608|FontID=1|IsHidden=T|Text=0603|Name=Package Reference
|RECORD=41|OwnerIndex=407|IndexInSheet=4|OwnerPartId=-1|Location.X=767|Location.Y=542|Color=8388608|FontID=1|IsHidden=T|Text=RC|Name=Series
|RECORD=41|OwnerIndex=407|IndexInSheet=5|OwnerPartId=-1|Location.X=767|Location.Y=542|Color=8388608|FontID=1|IsHidden=T|Text=100mW|Name=Power Rating
|RECORD=41|OwnerIndex=407|IndexInSheet=6|OwnerPartId=-1|Location.X=767|Location.Y=542|Color=8388608|FontID=1|IsHidden=T|Text=Yageo|Name=Manufacturer
|RECORD=41|OwnerIndex=407|IndexInSheet=7|OwnerPartId=-1|Location.X=767|Location.Y=542|Color=8388608|FontID=1|IsHidden=T|Text=100PPM/C|Name=Temperature Coefficient
|RECORD=41|OwnerIndex=407|IndexInSheet=8|OwnerPartId=-1|Location.X=767|Location.Y=542|Color=8388608|FontID=1|IsHidden=T|Text=4.7kOhms|Name=Resistance
|RECORD=41|OwnerIndex=407|IndexInSheet=9|OwnerPartId=-1|Location.X=767|Location.Y=542|Color=8388608|FontID=1|IsHidden=T|Text=Rev. 7, 05/2017|Name=Datasheet Version
|RECORD=41|OwnerIndex=407|IndexInSheet=10|OwnerPartId=-1|Location.X=767|Location.Y=542|Color=8388608|FontID=1|IsHidden=T|Text=Reel|Name=Packaging
|RECORD=41|OwnerIndex=407|IndexInSheet=11|OwnerPartId=-1|Location.X=767|Location.Y=542|Color=8388608|FontID=1|IsHidden=T|Text=SMD/SMT|Name=Termination Style
|RECORD=41|OwnerIndex=407|IndexInSheet=12|OwnerPartId=-1|Location.X=767|Location.Y=542|Color=8388608|FontID=2|IsHidden=T|Text=http://www.yageo.com/documents/recent/PYu-RC_Group_51_RoHS_L_7.pdf|Name=Datasheet URL
|RECORD=41|OwnerIndex=407|IndexInSheet=13|OwnerPartId=-1|Location.X=767|Location.Y=542|Color=8388608|FontID=2|IsHidden=T|Text=http://www.yageo.com/|Name=Manufacturer URL
|RECORD=41|OwnerIndex=407|IndexInSheet=14|OwnerPartId=-1|Location.X=767|Location.Y=542|Color=8388608|FontID=1|IsHidden=T|Text=2-Pin Surface Mount Device, Body 1.6 x 0.8 mm|Name=Package Description
|RECORD=41|OwnerIndex=407|IndexInSheet=15|OwnerPartId=-1|Location.X=767|Location.Y=542|Color=8388608|FontID=1|IsHidden=T|Text=1608|Name=Case Code - mm
|RECORD=41|OwnerIndex=407|IndexInSheet=16|OwnerPartId=-1|Location.X=767|Location.Y=542|Color=8388608|FontID=1|IsHidden=T|Text=50V|Name=Voltage Rating
|RECORD=41|OwnerIndex=407|IndexInSheet=17|OwnerPartId=-1|Location.X=767|Location.Y=542|Color=8388608|FontID=1|IsHidden=T|Text=0603|Name=Case Code - in
|RECORD=41|OwnerIndex=407|IndexInSheet=18|OwnerPartId=-1|Location.X=767|Location.Y=542|Color=8388608|FontID=1|IsHidden=T|Text=SurfaceMount|Name=Mounting Technology
|RECORD=41|OwnerIndex=407|IndexInSheet=19|OwnerPartId=-1|Location.X=767|Location.Y=542|Color=8388608|FontID=1|IsHidden=T|Text=-55Cto+155C|Name=Operating Temperature Range
|RECORD=41|OwnerIndex=407|IndexInSheet=20|OwnerPartId=-1|Location.X=767|Location.Y=542|Color=8388608|FontID=1|IsHidden=T|Text=1%|Name=Tolerance
|RECORD=41|OwnerIndex=407|IndexInSheet=21|OwnerPartId=-1|Location.X=767|Location.Y=542|Color=8388608|FontID=1|IsHidden=T|Text=ThickFilmResistorsGeneralPurpose|Name=Product
|RECORD=34|OwnerIndex=407|IndexInSheet=-1|OwnerPartId=-1|Location.X=773|Location.Y=521|Color=8388608|FontID=1|Text=R11|Name=Designator|ReadOnlyState=1
|RECORD=41|OwnerIndex=407|IndexInSheet=-1|OwnerPartId=-1|Location.X=773|Location.Y=511|Color=8388608|FontID=1|Text=4.7K|Name=Comment
|RECORD=44|OwnerIndex=407
|RECORD=45|OwnerIndex=434|IndexInSheet=-1|Description=Chip Resistor, 2-Leads, Body 1.60x0.80mm, IPC High Density|UseComponentLibrary=T|ModelName=RESC1608X55X25LL10T15|ModelType=PCBLIB|DatafileCount=1|ModelDatafileEntity0=RESC1608X55X25LL10T15|ModelDatafileKind0=PCBLib|IsCurrent=T|DatalinksLocked=T|DatabaseDatalinksLocked=T
|RECORD=46|OwnerIndex=435
|RECORD=48|OwnerIndex=435
|RECORD=41|OwnerIndex=437|IndexInSheet=-1|OwnerPartId=-1|Color=8388608|FontID=1|IsHidden=T|Text=2D|Name=Available Preview Images
|RECORD=45|OwnerIndex=434|IndexInSheet=-1|Description=Chip Resistor, 2-Leads, Body 1.70x0.90mm, IPC Low Density|UseComponentLibrary=T|ModelName=RESC1608X55X25ML10T15|ModelType=PCBLIB|DatafileCount=1|ModelDatafileEntity0=RESC1608X55X25ML10T15|ModelDatafileKind0=PCBLib|DatalinksLocked=T|DatabaseDatalinksLocked=T
|RECORD=46|OwnerIndex=439
|RECORD=48|OwnerIndex=439
|RECORD=41|OwnerIndex=441|IndexInSheet=-1|OwnerPartId=-1|Color=8388608|FontID=1|IsHidden=T|Text=2D|Name=Available Preview Images
|RECORD=45|OwnerIndex=434|IndexInSheet=-1|Description=Chip Resistor, 2-Leads, Body 1.70x0.90mm, IPC Medium Density|UseComponentLibrary=T|ModelName=RESC1608X55X25NL10T15|ModelType=PCBLIB|DatafileCount=1|ModelDatafileEntity0=RESC1608X55X25NL10T15|ModelDatafileKind0=PCBLib|DatalinksLocked=T|DatabaseDatalinksLocked=T
|RECORD=46|OwnerIndex=443
|RECORD=48|OwnerIndex=443
|RECORD=41|OwnerIndex=445|IndexInSheet=-1|OwnerPartId=-1|Color=8388608|FontID=1|IsHidden=T|Text=2D|Name=Available Preview Images
|RECORD=1|LibReference=RES-2|ComponentDescription=Chip Resistor, 4.7 KOhm, +/- 1%, 0.1 W, -55 to 155 degC, 0603 (1608 Metric), RoHS, Tape and Reel RC0603FR-074K7L|PartCount=2|DisplayModeCount=1|IndexInSheet=67|OwnerPartId=-1|Location.X=740|Location.Y=510|Orientation=1|CurrentPartId=1|LibraryPath=*|SourceLibraryName=Altium Content Vault|TargetFileName=*|AreaColor=11599871|Color=128|PartIDLocked=T|DesignItemId=CMP-2000-06942-1|AllPinCount=2
|RECORD=2|OwnerIndex=447|OwnerPartId=1|FormalType=1|Electrical=4|PinConglomerate=33|PinLength=10|Location.X=740|Location.Y=530|Name=2|Designator=2|PinPropagationDelay=0.000000E+000
|RECORD=2|OwnerIndex=447|OwnerPartId=1|FormalType=1|Electrical=4|PinConglomerate=35|PinLength=10|Location.X=740|Location.Y=510|Name=1|Designator=1|PinPropagationDelay=0.000000E+000
|RECORD=6|OwnerIndex=447|IsNotAccesible=T|IndexInSheet=2|OwnerPartId=1|LineWidth=1|Color=16711680|LocationCount=10|X1=740|Y1=530|X2=740|Y2=526|X3=742|Y3=525|X4=738|Y4=523|X5=742|Y5=521|X6=738|Y6=519|X7=742|Y7=517|X8=738|Y8=515|X9=740|Y9=514|X10=740|Y10=510
|RECORD=41|OwnerIndex=447|IndexInSheet=3|OwnerPartId=-1|Location.X=737|Location.Y=542|Color=8388608|FontID=1|IsHidden=T|Text=0603|Name=Package Reference
|RECORD=41|OwnerIndex=447|IndexInSheet=4|OwnerPartId=-1|Location.X=737|Location.Y=542|Color=8388608|FontID=1|IsHidden=T|Text=RC|Name=Series
|RECORD=41|OwnerIndex=447|IndexInSheet=5|OwnerPartId=-1|Location.X=737|Location.Y=542|Color=8388608|FontID=1|IsHidden=T|Text=100mW|Name=Power Rating
|RECORD=41|OwnerIndex=447|IndexInSheet=6|OwnerPartId=-1|Location.X=737|Location.Y=542|Color=8388608|FontID=1|IsHidden=T|Text=Yageo|Name=Manufacturer
|RECORD=41|OwnerIndex=447|IndexInSheet=7|OwnerPartId=-1|Location.X=737|Location.Y=542|Color=8388608|FontID=1|IsHidden=T|Text=100PPM/C|Name=Temperature Coefficient
|RECORD=41|OwnerIndex=447|IndexInSheet=8|OwnerPartId=-1|Location.X=737|Location.Y=542|Color=8388608|FontID=1|IsHidden=T|Text=4.7kOhms|Name=Resistance
|RECORD=41|OwnerIndex=447|IndexInSheet=9|OwnerPartId=-1|Location.X=737|Location.Y=542|Color=8388608|FontID=1|IsHidden=T|Text=Rev. 7, 05/2017|Name=Datasheet Version
|RECORD=41|OwnerIndex=447|IndexInSheet=10|OwnerPartId=-1|Location.X=737|Location.Y=542|Color=8388608|FontID=1|IsHidden=T|Text=Reel|Name=Packaging
|RECORD=41|OwnerIndex=447|IndexInSheet=11|OwnerPartId=-1|Location.X=737|Location.Y=542|Color=8388608|FontID=1|IsHidden=T|Text=SMD/SMT|Name=Termination Style
|RECORD=41|OwnerIndex=447|IndexInSheet=12|OwnerPartId=-1|Location.X=737|Location.Y=542|Color=8388608|FontID=2|IsHidden=T|Text=http://www.yageo.com/documents/recent/PYu-RC_Group_51_RoHS_L_7.pdf|Name=Datasheet URL
|RECORD=41|OwnerIndex=447|IndexInSheet=13|OwnerPartId=-1|Location.X=737|Location.Y=542|Color=8388608|FontID=2|IsHidden=T|Text=http://www.yageo.com/|Name=Manufacturer URL
|RECORD=41|OwnerIndex=447|IndexInSheet=14|OwnerPartId=-1|Location.X=737|Location.Y=542|Color=8388608|FontID=1|IsHidden=T|Text=2-Pin Surface Mount Device, Body 1.6 x 0.8 mm|Name=Package Description
|RECORD=41|OwnerIndex=447|IndexInSheet=15|OwnerPartId=-1|Location.X=737|Location.Y=542|Color=8388608|FontID=1|IsHidden=T|Text=1608|Name=Case Code - mm
|RECORD=41|OwnerIndex=447|IndexInSheet=16|OwnerPartId=-1|Location.X=737|Location.Y=542|Color=8388608|FontID=1|IsHidden=T|Text=50V|Name=Voltage Rating
|RECORD=41|OwnerIndex=447|IndexInSheet=17|OwnerPartId=-1|Location.X=737|Location.Y=542|Color=8388608|FontID=1|IsHidden=T|Text=0603|Name=Case Code - in
|RECORD=41|OwnerIndex=447|IndexInSheet=18|OwnerPartId=-1|Location.X=737|Location.Y=542|Color=8388608|FontID=1|IsHidden=T|Text=SurfaceMount|Name=Mounting Technology
|RECORD=41|OwnerIndex=447|IndexInSheet=19|OwnerPartId=-1|Location.X=737|Location.Y=542|Color=8388608|FontID=1|IsHidden=T|Text=-55Cto+155C|Name=Operating Temperature Range
|RECORD=41|OwnerIndex=447|IndexInSheet=20|OwnerPartId=-1|Location.X=737|Location.Y=542|Color=8388608|FontID=1|IsHidden=T|Text=1%|Name=Tolerance
|RECORD=41|OwnerIndex=447|IndexInSheet=21|OwnerPartId=-1|Location.X=737|Location.Y=542|Color=8388608|FontID=1|IsHidden=T|Text=ThickFilmResistorsGeneralPurpose|Name=Product
|RECORD=34|OwnerIndex=447|IndexInSheet=-1|OwnerPartId=-1|Location.X=743|Location.Y=521|Color=8388608|FontID=1|Text=R10|Name=Designator|ReadOnlyState=1
|RECORD=41|OwnerIndex=447|IndexInSheet=-1|OwnerPartId=-1|Location.X=743|Location.Y=511|Color=8388608|FontID=1|Text=4.7K|Name=Comment
|RECORD=44|OwnerIndex=447
|RECORD=45|OwnerIndex=474|IndexInSheet=-1|Description=Chip Resistor, 2-Leads, Body 1.60x0.80mm, IPC High Density|UseComponentLibrary=T|ModelName=RESC1608X55X25LL10T15|ModelType=PCBLIB|DatafileCount=1|ModelDatafileEntity0=RESC1608X55X25LL10T15|ModelDatafileKind0=PCBLib|IsCurrent=T|DatalinksLocked=T|DatabaseDatalinksLocked=T
|RECORD=46|OwnerIndex=475
|RECORD=48|OwnerIndex=475
|RECORD=41|OwnerIndex=477|IndexInSheet=-1|OwnerPartId=-1|Color=8388608|FontID=1|IsHidden=T|Text=2D|Name=Available Preview Images
|RECORD=45|OwnerIndex=474|IndexInSheet=-1|Description=Chip Resistor, 2-Leads, Body 1.70x0.90mm, IPC Low Density|UseComponentLibrary=T|ModelName=RESC1608X55X25ML10T15|ModelType=PCBLIB|DatafileCount=1|ModelDatafileEntity0=RESC1608X55X25ML10T15|ModelDatafileKind0=PCBLib|DatalinksLocked=T|DatabaseDatalinksLocked=T
|RECORD=46|OwnerIndex=479
|RECORD=48|OwnerIndex=479
|RECORD=41|OwnerIndex=481|IndexInSheet=-1|OwnerPartId=-1|Color=8388608|FontID=1|IsHidden=T|Text=2D|Name=Available Preview Images
|RECORD=45|OwnerIndex=474|IndexInSheet=-1|Description=Chip Resistor, 2-Leads, Body 1.70x0.90mm, IPC Medium Density|UseComponentLibrary=T|ModelName=RESC1608X55X25NL10T15|ModelType=PCBLIB|DatafileCount=1|ModelDatafileEntity0=RESC1608X55X25NL10T15|ModelDatafileKind0=PCBLib|DatalinksLocked=T|DatabaseDatalinksLocked=T
|RECORD=46|OwnerIndex=483
|RECORD=48|OwnerIndex=483
|RECORD=41|OwnerIndex=485|IndexInSheet=-1|OwnerPartId=-1|Color=8388608|FontID=1|IsHidden=T|Text=2D|Name=Available Preview Images
|RECORD=1|LibReference=CAP|ComponentDescription=C0603X104K5RACAUTO|PartCount=2|DisplayModeCount=2|IndexInSheet=68|OwnerPartId=-1|Location.X=800|Location.Y=510|Orientation=1|CurrentPartId=1|SourceLibraryName=Altium Content Vault|TargetFileName=*|AreaColor=11599871|Color=128|PartIDLocked=F|DesignItemId=CMP-2006-00003-1|AllPinCount=2
|RECORD=2|OwnerIndex=487|OwnerPartId=1|OwnerPartDisplayMode=1|FormalType=1|Electrical=4|PinConglomerate=35|PinLength=10|Location.X=810|Location.Y=510|Name=1|Designator=1|PinPropagationDelay=0.000000E+000
|RECORD=2|OwnerIndex=487|OwnerPartId=1|OwnerPartDisplayMode=1|FormalType=1|Electrical=4|PinConglomerate=33|PinLength=10|Location.X=810|Location.Y=520|Name=2|Designator=2|PinPropagationDelay=0.000000E+000
|RECORD=13|OwnerIndex=487|IsNotAccesible=T|IndexInSheet=2|OwnerPartId=1|OwnerPartDisplayMode=1|Location.X=818|Location.Y=510|Corner.X=802|Corner.Y=510|LineWidth=1|Color=16711680
|RECORD=13|OwnerIndex=487|IsNotAccesible=T|IndexInSheet=3|OwnerPartId=1|OwnerPartDisplayMode=1|Location.X=810|Location.Y=514|Corner.X=810|Corner.Y=520|LineWidth=1|Color=16711680
|RECORD=12|OwnerIndex=487|IsNotAccesible=T|IndexInSheet=4|OwnerPartId=1|OwnerPartDisplayMode=1|Location.X=810|Location.Y=530|Radius=16|LineWidth=1|StartAngle=241.000|EndAngle=270.000|Color=16711680
|RECORD=12|OwnerIndex=487|IsNotAccesible=T|IndexInSheet=5|OwnerPartId=1|OwnerPartDisplayMode=1|Location.X=810|Location.Y=530|Radius=16|LineWidth=1|StartAngle=270.000|EndAngle=299.000|Color=16711680
|RECORD=2|OwnerIndex=487|OwnerPartId=1|FormalType=1|Electrical=4|PinConglomerate=35|PinLength=10|Location.X=810|Location.Y=510|Name=1|Designator=1|PinPropagationDelay=0.000000E+000
|RECORD=2|OwnerIndex=487|OwnerPartId=1|FormalType=1|Electrical=4|PinConglomerate=33|PinLength=10|Location.X=810|Location.Y=520|Name=2|Designator=2|PinPropagationDelay=0.000000E+000
|RECORD=13|OwnerIndex=487|IsNotAccesible=T|IndexInSheet=8|OwnerPartId=1|Location.X=802|Location.Y=517|Corner.X=818|Corner.Y=517|LineWidth=1|Color=16711680
|RECORD=13|OwnerIndex=487|IsNotAccesible=T|IndexInSheet=9|OwnerPartId=1|Location.X=818|Location.Y=513|Corner.X=802|Corner.Y=513|LineWidth=1|Color=16711680
|RECORD=6|OwnerIndex=487|IsNotAccesible=T|IndexInSheet=10|OwnerPartId=1|LineWidth=1|Color=16711680|LocationCount=2|X1=810|Y1=510|X2=810|Y2=513
|RECORD=6|OwnerIndex=487|IsNotAccesible=T|IndexInSheet=11|OwnerPartId=1|LineWidth=1|Color=16711680|LocationCount=2|X1=810|Y1=520|X2=810|Y2=517
|RECORD=41|OwnerIndex=487|IndexInSheet=12|OwnerPartId=-1|Location.X=801|Location.Y=532|Color=8388608|FontID=1|IsHidden=T|Text=Kemet|Name=Manufacturer
|RECORD=41|OwnerIndex=487|IndexInSheet=13|OwnerPartId=-1|Location.X=801|Location.Y=532|Color=8388608|FontID=1|IsHidden=T|Text=C0603X104K5RACAUTO|Name=Part Number
|RECORD=34|OwnerIndex=487|IndexInSheet=-1|OwnerPartId=-1|Location.X=819|Location.Y=511|Color=8388608|FontID=4|Text=C23|Name=Designator|ReadOnlyState=1
|RECORD=41|OwnerIndex=487|IndexInSheet=-1|OwnerPartId=-1|Location.X=819|Location.Y=501|Color=8388608|FontID=4|Text=0.1uF|Name=Comment
|RECORD=44|OwnerIndex=487
|RECORD=45|OwnerIndex=508|IndexInSheet=-1|Description=Chip Capacitor, 2-Leads, Body 1.60x0.80mm, IPC Low Density|UseComponentLibrary=T|ModelName=CAPC1608X87X45ML20T05|ModelType=PCBLIB|DatafileCount=1|ModelDatafileEntity0=CAPC1608X87X45ML20T05|ModelDatafileKind0=PCBLib|IsCurrent=T|DatalinksLocked=T|DatabaseDatalinksLocked=T
|RECORD=46|OwnerIndex=509
|RECORD=48|OwnerIndex=509
|RECORD=41|OwnerIndex=511|IndexInSheet=-1|OwnerPartId=-1|Color=8388608|FontID=1|Text=2D|Name=Available Preview Images
|RECORD=45|OwnerIndex=508|IndexInSheet=-1|Description=Chip Capacitor, 2-Leads, Body 1.60x0.80mm, IPC High Density|UseComponentLibrary=T|ModelName=CAPC1608X87X45LL20T05|ModelType=PCBLIB|DatafileCount=1|ModelDatafileEntity0=CAPC1608X87X45LL20T05|ModelDatafileKind0=PCBLib|DatalinksLocked=T|DatabaseDatalinksLocked=T
|RECORD=46|OwnerIndex=513
|RECORD=48|OwnerIndex=513
|RECORD=41|OwnerIndex=515|IndexInSheet=-1|OwnerPartId=-1|Color=8388608|FontID=1|Text=2D|Name=Available Preview Images
|RECORD=45|OwnerIndex=508|IndexInSheet=-1|Description=Chip Capacitor, 2-Leads, Body 1.60x0.80mm, IPC Medium Density|UseComponentLibrary=T|ModelName=CAPC1608X87X45NL20T05|ModelType=PCBLIB|DatafileCount=1|ModelDatafileEntity0=CAPC1608X87X45NL20T05|ModelDatafileKind0=PCBLib|DatalinksLocked=T|DatabaseDatalinksLocked=T
|RECORD=46|OwnerIndex=517
|RECORD=48|OwnerIndex=517
|RECORD=41|OwnerIndex=519|IndexInSheet=-1|OwnerPartId=-1|Color=8388608|FontID=1|Text=2D|Name=Available Preview Images
|RECORD=17|IndexInSheet=69|OwnerPartId=-1|Style=4|ShowNetName=T|Location.X=810|Location.Y=480|Orientation=3|Color=128|FontID=1|Text=GND
|RECORD=17|IndexInSheet=70|OwnerPartId=-1|Style=4|ShowNetName=T|Location.X=770|Location.Y=480|Orientation=3|Color=128|FontID=1|Text=GND
|RECORD=17|IndexInSheet=71|OwnerPartId=-1|Style=4|ShowNetName=T|Location.X=740|Location.Y=480|Orientation=3|Color=128|FontID=1|Text=GND
|RECORD=17|IndexInSheet=72|OwnerPartId=-1|ShowNetName=T|Location.X=810|Location.Y=630|Orientation=1|Color=128|FontID=1|Text=+3.3V
|RECORD=17|IndexInSheet=73|OwnerPartId=-1|ShowNetName=T|Location.X=1010|Location.Y=590|Color=255|FontID=1|Text=MAC_PPS_IN1-|IsCrossSheetConnector=T
|RECORD=17|IndexInSheet=74|OwnerPartId=-1|ShowNetName=T|Location.X=1010|Location.Y=600|Color=255|FontID=1|Text=MAC_PPS_IN1+|IsCrossSheetConnector=T
|RECORD=17|IndexInSheet=75|OwnerPartId=-1|ShowNetName=T|Location.X=1010|Location.Y=560|Color=255|FontID=1|Text=MAC_PPS_IN0-|IsCrossSheetConnector=T
|RECORD=17|IndexInSheet=76|OwnerPartId=-1|ShowNetName=T|Location.X=1010|Location.Y=570|Color=255|FontID=1|Text=MAC_PPS_IN0+|IsCrossSheetConnector=T
|RECORD=17|IndexInSheet=77|OwnerPartId=-1|Style=4|ShowNetName=T|Location.X=990|Location.Y=480|Orientation=3|Color=128|FontID=1|Text=GND
|RECORD=17|IndexInSheet=78|OwnerPartId=-1|ShowNetName=T|Location.X=720|Location.Y=840|Orientation=2|Color=255|FontID=1|Text=MAC_PPS_IN1-|IsCrossSheetConnector=T
|RECORD=17|IndexInSheet=79|OwnerPartId=-1|ShowNetName=T|Location.X=720|Location.Y=850|Orientation=2|Color=255|FontID=1|Text=MAC_PPS_IN1+|IsCrossSheetConnector=T
|RECORD=17|IndexInSheet=80|OwnerPartId=-1|ShowNetName=T|Location.X=720|Location.Y=820|Orientation=2|Color=255|FontID=1|Text=MAC_PPS_IN0-|IsCrossSheetConnector=T
|RECORD=17|IndexInSheet=81|OwnerPartId=-1|ShowNetName=T|Location.X=720|Location.Y=830|Orientation=2|Color=255|FontID=1|Text=MAC_PPS_IN0+|IsCrossSheetConnector=T
|RECORD=1|LibReference=RES|PartCount=2|DisplayModeCount=2|IndexInSheet=82|OwnerPartId=-1|Location.X=710|Location.Y=330|Orientation=1|CurrentPartId=1|SourceLibraryName=Altium Content Vault|TargetFileName=*|AreaColor=11599871|Color=128|PartIDLocked=F|DesignItemId=CMP-2000-03854-1|AllPinCount=2
|RECORD=2|OwnerIndex=534|OwnerPartId=1|OwnerPartDisplayMode=1|FormalType=1|Electrical=4|PinConglomerate=33|PinLength=10|Location.X=720|Location.Y=350|Name=2|Designator=2|PinPropagationDelay=0.000000E+000
|RECORD=2|OwnerIndex=534|OwnerPartId=1|OwnerPartDisplayMode=1|FormalType=1|Electrical=4|PinConglomerate=35|PinLength=10|Location.X=720|Location.Y=330|Name=1|Designator=1|PinPropagationDelay=0.000000E+000
|RECORD=14|OwnerIndex=534|IsNotAccesible=T|IndexInSheet=2|OwnerPartId=1|OwnerPartDisplayMode=1|Location.X=716|Location.Y=330|Corner.X=724|Corner.Y=350|LineWidth=1|Color=16711680|AreaColor=11599871
|RECORD=2|OwnerIndex=534|OwnerPartId=1|FormalType=1|Electrical=4|PinConglomerate=33|PinLength=10|Location.X=720|Location.Y=350|Name=2|Designator=2|PinPropagationDelay=0.000000E+000
|RECORD=2|OwnerIndex=534|OwnerPartId=1|FormalType=1|Electrical=4|PinConglomerate=35|PinLength=10|Location.X=720|Location.Y=330|Name=1|Designator=1|PinPropagationDelay=0.000000E+000
|RECORD=6|OwnerIndex=534|IsNotAccesible=T|IndexInSheet=5|OwnerPartId=1|LineWidth=1|Color=16711680|LocationCount=10|X1=720|Y1=350|X2=720|Y2=346|X3=722|Y3=345|X4=718|Y4=343|X5=722|Y5=341|X6=718|Y6=339|X7=722|Y7=337|X8=718|Y8=335|X9=720|Y9=334|X10=720|Y10=330
|RECORD=41|OwnerIndex=534|IndexInSheet=6|OwnerPartId=-1|Location.X=717|Location.Y=362|Color=8388608|FontID=1|IsHidden=T|Text=CRCW0603110RFKEA|Name=Part Number
|RECORD=41|OwnerIndex=534|IndexInSheet=7|OwnerPartId=-1|Location.X=717|Location.Y=362|Color=8388608|FontID=1|IsHidden=T|Text=Vishay Dale|Name=Manufacturer
|RECORD=34|OwnerIndex=534|IndexInSheet=-1|OwnerPartId=-1|Location.X=723|Location.Y=341|Color=8388608|FontID=1|Text=R12|Name=Designator|ReadOnlyState=1
|RECORD=41|OwnerIndex=534|IndexInSheet=-1|OwnerPartId=-1|Location.X=723|Location.Y=331|Color=8388608|FontID=1|Text=110R|Name=Comment
|RECORD=44|OwnerIndex=534
|RECORD=45|OwnerIndex=549|IndexInSheet=-1|Description=Chip Resistor, 2-Leads, Body 1.55x0.85mm, IPC Medium Density|UseComponentLibrary=T|ModelName=RESC1609X50X30NL10T20|ModelType=PCBLIB|DatafileCount=1|ModelDatafileEntity0=RESC1609X50X30NL10T20|ModelDatafileKind0=PCBLib|IsCurrent=T|DatalinksLocked=T|DatabaseDatalinksLocked=T
|RECORD=46|OwnerIndex=550
|RECORD=48|OwnerIndex=550
|RECORD=41|OwnerIndex=552|IndexInSheet=-1|OwnerPartId=-1|Color=8388608|FontID=1|IsHidden=T|Text=2D|Name=Available Preview Images
|RECORD=45|OwnerIndex=549|IndexInSheet=-1|Description=Chip Resistor, 2-Leads, Body 1.55x0.85mm, IPC High Density|UseComponentLibrary=T|ModelName=RESC1609X50X30LL10T20|ModelType=PCBLIB|DatafileCount=1|ModelDatafileEntity0=RESC1609X50X30LL10T20|ModelDatafileKind0=PCBLib|DatalinksLocked=T|DatabaseDatalinksLocked=T
|RECORD=46|OwnerIndex=554
|RECORD=48|OwnerIndex=554
|RECORD=41|OwnerIndex=556|IndexInSheet=-1|OwnerPartId=-1|Color=8388608|FontID=1|IsHidden=T|Text=2D|Name=Available Preview Images
|RECORD=45|OwnerIndex=549|IndexInSheet=-1|Description=Chip Resistor, 2-Leads, Body 1.55x0.85mm, IPC Low Density|UseComponentLibrary=T|ModelName=RESC1609X50X30ML10T20|ModelType=PCBLIB|DatafileCount=1|ModelDatafileEntity0=RESC1609X50X30ML10T20|ModelDatafileKind0=PCBLib|DatalinksLocked=T|DatabaseDatalinksLocked=T
|RECORD=46|OwnerIndex=558
|RECORD=48|OwnerIndex=558
|RECORD=41|OwnerIndex=560|IndexInSheet=-1|OwnerPartId=-1|Color=8388608|FontID=1|IsHidden=T|Text=2D|Name=Available Preview Images
|RECORD=1|LibReference=CAP|ComponentDescription=C0603X104K5RACAUTO|PartCount=2|DisplayModeCount=2|IndexInSheet=83|OwnerPartId=-1|Location.X=790|Location.Y=240|Orientation=3|CurrentPartId=1|SourceLibraryName=Altium Content Vault|TargetFileName=*|AreaColor=11599871|Color=128|PartIDLocked=F|DesignItemId=CMP-2006-00003-1|AllPinCount=2
|RECORD=2|OwnerIndex=562|OwnerPartId=1|OwnerPartDisplayMode=1|FormalType=1|Electrical=4|PinConglomerate=33|PinLength=10|Location.X=780|Location.Y=240|Name=1|Designator=1|PinPropagationDelay=0.000000E+000
|RECORD=2|OwnerIndex=562|OwnerPartId=1|OwnerPartDisplayMode=1|FormalType=1|Electrical=4|PinConglomerate=35|PinLength=10|Location.X=780|Location.Y=230|Name=2|Designator=2|PinPropagationDelay=0.000000E+000
|RECORD=13|OwnerIndex=562|IsNotAccesible=T|IndexInSheet=2|OwnerPartId=1|OwnerPartDisplayMode=1|Location.X=772|Location.Y=240|Corner.X=788|Corner.Y=240|LineWidth=1|Color=16711680
|RECORD=13|OwnerIndex=562|IsNotAccesible=T|IndexInSheet=3|OwnerPartId=1|OwnerPartDisplayMode=1|Location.X=780|Location.Y=236|Corner.X=780|Corner.Y=230|LineWidth=1|Color=16711680
|RECORD=12|OwnerIndex=562|IsNotAccesible=T|IndexInSheet=4|OwnerPartId=1|OwnerPartDisplayMode=1|Location.X=780|Location.Y=220|Radius=16|LineWidth=1|StartAngle=61.000|EndAngle=90.000|Color=16711680
|RECORD=12|OwnerIndex=562|IsNotAccesible=T|IndexInSheet=5|OwnerPartId=1|OwnerPartDisplayMode=1|Location.X=780|Location.Y=220|Radius=16|LineWidth=1|StartAngle=90.000|EndAngle=119.000|Color=16711680
|RECORD=2|OwnerIndex=562|OwnerPartId=1|FormalType=1|Electrical=4|PinConglomerate=33|PinLength=10|Location.X=780|Location.Y=240|Name=1|Designator=1|PinPropagationDelay=0.000000E+000
|RECORD=2|OwnerIndex=562|OwnerPartId=1|FormalType=1|Electrical=4|PinConglomerate=35|PinLength=10|Location.X=780|Location.Y=230|Name=2|Designator=2|PinPropagationDelay=0.000000E+000
|RECORD=13|OwnerIndex=562|IsNotAccesible=T|IndexInSheet=8|OwnerPartId=1|Location.X=788|Location.Y=233|Corner.X=772|Corner.Y=233|LineWidth=1|Color=16711680
|RECORD=13|OwnerIndex=562|IsNotAccesible=T|IndexInSheet=9|OwnerPartId=1|Location.X=772|Location.Y=237|Corner.X=788|Corner.Y=237|LineWidth=1|Color=16711680
|RECORD=6|OwnerIndex=562|IsNotAccesible=T|IndexInSheet=10|OwnerPartId=1|LineWidth=1|Color=16711680|LocationCount=2|X1=780|Y1=240|X2=780|Y2=237
|RECORD=6|OwnerIndex=562|IsNotAccesible=T|IndexInSheet=11|OwnerPartId=1|LineWidth=1|Color=16711680|LocationCount=2|X1=780|Y1=230|X2=780|Y2=233
|RECORD=41|OwnerIndex=562|IndexInSheet=12|OwnerPartId=-1|Location.X=771|Location.Y=252|Color=8388608|FontID=1|IsHidden=T|Text=Kemet|Name=Manufacturer
|RECORD=41|OwnerIndex=562|IndexInSheet=13|OwnerPartId=-1|Location.X=771|Location.Y=252|Color=8388608|FontID=1|IsHidden=T|Text=C0603X104K5RACAUTO|Name=Part Number
|RECORD=34|OwnerIndex=562|IndexInSheet=-1|OwnerPartId=-1|Location.X=789|Location.Y=227|Color=8388608|FontID=4|Text=C24|Name=Designator|ReadOnlyState=1
|RECORD=41|OwnerIndex=562|IndexInSheet=-1|OwnerPartId=-1|Location.X=789|Location.Y=213|Color=8388608|FontID=4|Text=0.1uF|Name=Comment
|RECORD=44|OwnerIndex=562
|RECORD=45|OwnerIndex=583|IndexInSheet=-1|Description=Chip Capacitor, 2-Leads, Body 1.60x0.80mm, IPC Low Density|UseComponentLibrary=T|ModelName=CAPC1608X87X45ML20T05|ModelType=PCBLIB|DatafileCount=1|ModelDatafileEntity0=CAPC1608X87X45ML20T05|ModelDatafileKind0=PCBLib|IsCurrent=T|DatalinksLocked=T|DatabaseDatalinksLocked=T
|RECORD=46|OwnerIndex=584
|RECORD=48|OwnerIndex=584
|RECORD=41|OwnerIndex=586|IndexInSheet=-1|OwnerPartId=-1|Color=8388608|FontID=1|Text=2D|Name=Available Preview Images
|RECORD=45|OwnerIndex=583|IndexInSheet=-1|Description=Chip Capacitor, 2-Leads, Body 1.60x0.80mm, IPC High Density|UseComponentLibrary=T|ModelName=CAPC1608X87X45LL20T05|ModelType=PCBLIB|DatafileCount=1|ModelDatafileEntity0=CAPC1608X87X45LL20T05|ModelDatafileKind0=PCBLib|DatalinksLocked=T|DatabaseDatalinksLocked=T
|RECORD=46|OwnerIndex=588
|RECORD=48|OwnerIndex=588
|RECORD=41|OwnerIndex=590|IndexInSheet=-1|OwnerPartId=-1|Color=8388608|FontID=1|Text=2D|Name=Available Preview Images
|RECORD=45|OwnerIndex=583|IndexInSheet=-1|Description=Chip Capacitor, 2-Leads, Body 1.60x0.80mm, IPC Medium Density|UseComponentLibrary=T|ModelName=CAPC1608X87X45NL20T05|ModelType=PCBLIB|DatafileCount=1|ModelDatafileEntity0=CAPC1608X87X45NL20T05|ModelDatafileKind0=PCBLib|DatalinksLocked=T|DatabaseDatalinksLocked=T
|RECORD=46|OwnerIndex=592
|RECORD=48|OwnerIndex=592
|RECORD=41|OwnerIndex=594|IndexInSheet=-1|OwnerPartId=-1|Color=8388608|FontID=1|Text=2D|Name=Available Preview Images
|RECORD=17|IndexInSheet=84|OwnerPartId=-1|ShowNetName=T|Location.X=780|Location.Y=390|Orientation=1|Color=128|FontID=1|Text=+3.3V
|RECORD=17|IndexInSheet=85|OwnerPartId=-1|Style=4|ShowNetName=T|Location.X=780|Location.Y=190|Orientation=3|Color=128|FontID=1|Text=GND
|RECORD=17|IndexInSheet=86|OwnerPartId=-1|Style=4|ShowNetName=T|Location.X=970|Location.Y=190|Orientation=3|Color=128|FontID=1|Text=GND
|RECORD=22|IndexInSheet=87|OwnerPartId=-1|Location.X=810|Location.Y=300|Color=255|Orientation=1|Symbol=Thin Cross|IsActive=T|SuppressAll=T
|RECORD=22|IndexInSheet=88|OwnerPartId=-1|Location.X=810|Location.Y=290|Color=255|Orientation=1|Symbol=Thin Cross|IsActive=T|SuppressAll=T
|RECORD=22|IndexInSheet=89|OwnerPartId=-1|Location.X=930|Location.Y=300|Color=255|Orientation=1|Symbol=Thin Cross|IsActive=T|SuppressAll=T
|RECORD=1|LibReference=RES-2|ComponentDescription=General Purpose Chip Resistor, 49.9 Ohm, +/- 1%, -55 to 155 degC, 0603 (1608 Metric), RoHS, Tape and Reel|PartCount=2|DisplayModeCount=1|IndexInSheet=90|OwnerPartId=-1|Location.X=960|Location.Y=330|CurrentPartId=1|LibraryPath=*|SourceLibraryName=Altium Content Vault|TargetFileName=*|AreaColor=11599871|Color=128|PartIDLocked=T|DesignItemId=CMP-1659-00036-1|AllPinCount=2
|RECORD=2|OwnerIndex=602|OwnerPartId=1|FormalType=1|Electrical=4|PinConglomerate=32|PinLength=10|Location.X=980|Location.Y=330|Name=2|Designator=2|PinPropagationDelay=0.000000E+000
|RECORD=2|OwnerIndex=602|OwnerPartId=1|FormalType=1|Electrical=4|PinConglomerate=34|PinLength=10|Location.X=960|Location.Y=330|Name=1|Designator=1|PinPropagationDelay=0.000000E+000
|RECORD=6|OwnerIndex=602|IsNotAccesible=T|IndexInSheet=2|OwnerPartId=1|LineWidth=1|Color=16711680|LocationCount=10|X1=980|Y1=330|X2=976|Y2=330|X3=975|Y3=328|X4=973|Y4=332|X5=971|Y5=328|X6=969|Y6=332|X7=967|Y7=328|X8=965|Y8=332|X9=964|Y9=330|X10=960|Y10=330
|RECORD=41|OwnerIndex=602|IndexInSheet=3|OwnerPartId=-1|Location.X=948|Location.Y=345|Color=8388608|FontID=1|IsHidden=T|Text=0603|Name=PackageReference
|RECORD=41|OwnerIndex=602|IndexInSheet=4|OwnerPartId=-1|Location.X=948|Location.Y=345|Color=8388608|FontID=1|IsHidden=T|Text=Tray|Name=Packaging
|RECORD=41|OwnerIndex=602|IndexInSheet=5|OwnerPartId=-1|Location.X=948|Location.Y=345|Color=8388608|FontID=1|IsHidden=T|Text=Datasheet|Name=ComponentLink2Description
|RECORD=41|OwnerIndex=602|IndexInSheet=6|OwnerPartId=-1|Location.X=948|Location.Y=345|Color=8388608|FontID=1|IsHidden=T|Text=Manufacturer URL|Name=ComponentLink1Description
|RECORD=41|OwnerIndex=602|IndexInSheet=7|OwnerPartId=-1|Location.X=948|Location.Y=345|Color=8388608|FontID=2|IsHidden=T|Text=https://datasheet.ciiva.com/11808/0900766b80f96399-11808223.pdf|Name=ComponentLink2URL
|RECORD=41|OwnerIndex=602|IndexInSheet=8|OwnerPartId=-1|Location.X=948|Location.Y=345|Color=8388608|FontID=1|IsHidden=T|Text=true|Name=RoHSCompliant
|RECORD=41|OwnerIndex=602|IndexInSheet=9|OwnerPartId=-1|Location.X=948|Location.Y=345|Color=8388608|FontID=1|IsHidden=T|Text=85 degC|Name=Max Operating Temperature
|RECORD=41|OwnerIndex=602|IndexInSheet=10|OwnerPartId=-1|Location.X=948|Location.Y=345|Color=8388608|FontID=1|IsHidden=T|Text=3.63 V|Name=Max Supply Voltage
|RECORD=41|OwnerIndex=602|IndexInSheet=11|OwnerPartId=-1|Location.X=948|Location.Y=345|Color=8388608|FontID=2|IsHidden=T|Text=http://www.yageo.com/|Name=ComponentLink1URL
|RECORD=41|OwnerIndex=602|IndexInSheet=12|OwnerPartId=-1|Location.X=948|Location.Y=345|Color=8388608|FontID=1|IsHidden=T|Text=2-Pin Surface Mount Device, Body 1.6 x 0.8 mm|Name=PackageDescription
|RECORD=41|OwnerIndex=602|IndexInSheet=13|OwnerPartId=-1|Location.X=948|Location.Y=345|Color=8388608|FontID=1|IsHidden=T|Text=LQFP|Name=Case\Package
|RECORD=41|OwnerIndex=602|IndexInSheet=14|OwnerPartId=-1|Location.X=948|Location.Y=345|Color=8388608|FontID=1|IsHidden=T|Text=Rev. 4, 04/2009|Name=DatasheetVersion
|RECORD=41|OwnerIndex=602|IndexInSheet=15|OwnerPartId=-1|Location.X=948|Location.Y=345|Color=8388608|FontID=1|IsHidden=T|Text=-40 degC|Name=Min Operating Temperature
|RECORD=41|OwnerIndex=602|IndexInSheet=16|OwnerPartId=-1|Location.X=948|Location.Y=345|Color=8388608|FontID=1|IsHidden=T|Text=SPI|Name=Interface
|RECORD=41|OwnerIndex=602|IndexInSheet=17|OwnerPartId=-1|Location.X=948|Location.Y=345|Color=8388608|FontID=1|IsHidden=T|Text=250|Name=Package Quantity
|RECORD=41|OwnerIndex=602|IndexInSheet=18|OwnerPartId=-1|Location.X=948|Location.Y=345|Color=8388608|FontID=1|IsHidden=T|Text=2.97 V|Name=Min Supply Voltage
|RECORD=41|OwnerIndex=602|IndexInSheet=19|OwnerPartId=-1|Location.X=948|Location.Y=345|Color=8388608|FontID=1|IsHidden=T|Text=48|Name=Pins
|RECORD=34|OwnerIndex=602|IndexInSheet=-1|OwnerPartId=-1|Location.X=959|Location.Y=333|Color=8388608|FontID=1|Text=R13|Name=Designator|ReadOnlyState=1
|RECORD=41|OwnerIndex=602|IndexInSheet=-1|OwnerPartId=-1|Location.X=959|Location.Y=317|Color=8388608|FontID=1|Text=49.9R|Name=Comment
|RECORD=44|OwnerIndex=602
|RECORD=45|OwnerIndex=627|IndexInSheet=-1|Description=Chip Resistor, 2-Leads, Body 1.70x0.90mm, IPC Medium Density|UseComponentLibrary=T|ModelName=RESC1608X55X25NL10T15|ModelType=PCBLIB|DatafileCount=1|ModelDatafileEntity0=RESC1608X55X25NL10T15|ModelDatafileKind0=PCBLib|IsCurrent=T|DatalinksLocked=T|DatabaseDatalinksLocked=T
|RECORD=46|OwnerIndex=628
|RECORD=48|OwnerIndex=628
|RECORD=41|OwnerIndex=630|IndexInSheet=-1|OwnerPartId=-1|Color=8388608|FontID=1|IsHidden=T|Text=2D|Name=Available Preview Images
|RECORD=45|OwnerIndex=627|IndexInSheet=-1|Description=Chip Resistor, 2-Leads, Body 1.70x0.90mm, IPC Low Density|UseComponentLibrary=T|ModelName=RESC1608X55X25ML10T15|ModelType=PCBLIB|DatafileCount=1|ModelDatafileEntity0=RESC1608X55X25ML10T15|ModelDatafileKind0=PCBLib|DatalinksLocked=T|DatabaseDatalinksLocked=T
|RECORD=46|OwnerIndex=632
|RECORD=48|OwnerIndex=632
|RECORD=41|OwnerIndex=634|IndexInSheet=-1|OwnerPartId=-1|Color=8388608|FontID=1|IsHidden=T|Text=2D|Name=Available Preview Images
|RECORD=45|OwnerIndex=627|IndexInSheet=-1|Description=Chip Resistor, 2-Leads, Body 1.70x0.90mm, IPC High Density|UseComponentLibrary=T|ModelName=RESC1608X55X25LL10T15|ModelType=PCBLIB|DatafileCount=1|ModelDatafileEntity0=RESC1608X55X25LL10T15|ModelDatafileKind0=PCBLib|DatalinksLocked=T|DatabaseDatalinksLocked=T
|RECORD=46|OwnerIndex=636
|RECORD=48|OwnerIndex=636
|RECORD=41|OwnerIndex=638|IndexInSheet=-1|OwnerPartId=-1|Color=8388608|FontID=1|IsHidden=T|Text=2D|Name=Available Preview Images
|RECORD=17|IndexInSheet=91|OwnerPartId=-1|ShowNetName=T|Location.X=1020|Location.Y=330|Color=255|FontID=1|Text=FPGA_MAC_PPS_OUT-|IsCrossSheetConnector=T
|RECORD=17|IndexInSheet=92|OwnerPartId=-1|ShowNetName=T|Location.X=1020|Location.Y=810|Color=255|FontID=1|Text=MAC_PPS_OUT+|IsCrossSheetConnector=T
|RECORD=17|IndexInSheet=93|OwnerPartId=-1|ShowNetName=T|Location.X=1020|Location.Y=800|Color=255|FontID=1|Text=MAC_PPS_OUT-|IsCrossSheetConnector=T
|RECORD=27|IndexInSheet=94|OwnerPartId=-1|LineWidth=1|Color=8388608|LocationCount=2|Y1=1100|X2=100|Y2=1100
|RECORD=27|IndexInSheet=95|OwnerPartId=-1|LineWidth=1|Color=8388608|LocationCount=2|X1=780|Y1=850|X2=720|Y2=850
|RECORD=27|IndexInSheet=96|OwnerPartId=-1|LineWidth=1|Color=8388608|LocationCount=2|X1=720|Y1=930|X2=770|Y2=930
|RECORD=27|IndexInSheet=97|OwnerPartId=-1|LineWidth=1|Color=8388608|LocationCount=2|X1=720|Y1=950|X2=770|Y2=950
|RECORD=27|IndexInSheet=98|OwnerPartId=-1|LineWidth=1|Color=8388608|LocationCount=2|X1=770|Y1=920|X2=750|Y2=920
|RECORD=27|IndexInSheet=99|OwnerPartId=-1|LineWidth=1|Color=8388608|LocationCount=4|X1=770|Y1=940|X2=750|Y2=940|X3=750|Y3=920|X4=750|Y4=900
|RECORD=27|IndexInSheet=100|OwnerPartId=-1|LineWidth=1|Color=8388608|LocationCount=2|X1=960|Y1=740|X2=980|Y2=740
|RECORD=27|IndexInSheet=101|OwnerPartId=-1|LineWidth=1|Color=8388608|LocationCount=2|X1=960|Y1=750|X2=980|Y2=750
|RECORD=27|IndexInSheet=102|OwnerPartId=-1|LineWidth=1|Color=8388608|LocationCount=5|X1=960|Y1=760|X2=980|Y2=760|X3=980|Y3=750|X4=980|Y4=740|X5=980|Y5=730
|RECORD=27|IndexInSheet=103|OwnerPartId=-1|LineWidth=1|Color=8388608|LocationCount=2|X1=960|Y1=780|X2=1020|Y2=780
|RECORD=27|IndexInSheet=104|OwnerPartId=-1|LineWidth=1|Color=8388608|LocationCount=2|X1=960|Y1=830|X2=1020|Y2=830
|RECORD=27|IndexInSheet=105|OwnerPartId=-1|LineWidth=1|Color=8388608|LocationCount=2|X1=1020|Y1=840|X2=960|Y2=840
|RECORD=27|IndexInSheet=106|OwnerPartId=-1|LineWidth=1|Color=8388608|LocationCount=2|X1=960|Y1=850|X2=1020|Y2=850
|RECORD=27|IndexInSheet=107|OwnerPartId=-1|LineWidth=1|Color=8388608|LocationCount=2|X1=980|Y1=920|X2=1100|Y2=920
|RECORD=27|IndexInSheet=108|OwnerPartId=-1|LineWidth=1|Color=8388608|LocationCount=2|X1=980|Y1=930|X2=1020|Y2=930
|RECORD=27|IndexInSheet=109|OwnerPartId=-1|LineWidth=1|Color=8388608|LocationCount=2|X1=980|Y1=940|X2=1020|Y2=940
|RECORD=27|IndexInSheet=110|OwnerPartId=-1|LineWidth=1|Color=8388608|LocationCount=2|X1=980|Y1=950|X2=1020|Y2=950
|RECORD=27|IndexInSheet=111|OwnerPartId=-1|LineWidth=1|Color=8388608|LocationCount=4|X1=1150|Y1=880|X2=1150|Y2=870|X3=1100|Y3=870|X4=1100|Y4=880
|RECORD=27|IndexInSheet=112|OwnerPartId=-1|LineWidth=1|Color=8388608|LocationCount=4|X1=1150|Y1=910|X2=1150|Y2=920|X3=1100|Y3=920|X4=1100|Y4=910
|RECORD=27|IndexInSheet=113|OwnerPartId=-1|LineWidth=1|Color=8388608|LocationCount=3|X1=700|Y1=570|X2=770|Y2=570|X3=840|Y3=570
|RECORD=27|IndexInSheet=114|OwnerPartId=-1|LineWidth=1|Color=8388608|LocationCount=2|X1=740|Y1=540|X2=740|Y2=600
|RECORD=27|IndexInSheet=115|OwnerPartId=-1|LineWidth=1|Color=8388608|LocationCount=2|X1=770|Y1=540|X2=770|Y2=570
|RECORD=27|IndexInSheet=116|OwnerPartId=-1|LineWidth=1|Color=8388608|LocationCount=3|X1=840|Y1=600|X2=740|Y2=600|X3=700|Y3=600
|RECORD=27|IndexInSheet=117|OwnerPartId=-1|LineWidth=1|Color=8388608|LocationCount=2|X1=740|Y1=480|X2=740|Y2=500
|RECORD=27|IndexInSheet=118|OwnerPartId=-1|LineWidth=1|Color=8388608|LocationCount=2|X1=770|Y1=480|X2=770|Y2=500
|RECORD=27|IndexInSheet=119|OwnerPartId=-1|LineWidth=1|Color=8388608|LocationCount=2|X1=810|Y1=480|X2=810|Y2=500
|RECORD=27|IndexInSheet=120|OwnerPartId=-1|LineWidth=1|Color=8388608|LocationCount=3|X1=810|Y1=530|X2=810|Y2=540|X3=840|Y3=540
|RECORD=27|IndexInSheet=121|OwnerPartId=-1|LineWidth=1|Color=8388608|LocationCount=2|X1=810|Y1=540|X2=810|Y2=630
|RECORD=27|IndexInSheet=122|OwnerPartId=-1|LineWidth=1|Color=8388608|LocationCount=2|X1=950|Y1=600|X2=1010|Y2=600
|RECORD=27|IndexInSheet=123|OwnerPartId=-1|LineWidth=1|Color=8388608|LocationCount=2|X1=950|Y1=590|X2=1010|Y2=590
|RECORD=27|IndexInSheet=124|OwnerPartId=-1|LineWidth=1|Color=8388608|LocationCount=2|X1=950|Y1=570|X2=1010|Y2=570
|RECORD=27|IndexInSheet=125|OwnerPartId=-1|LineWidth=1|Color=8388608|LocationCount=2|X1=950|Y1=560|X2=1010|Y2=560
|RECORD=27|IndexInSheet=126|OwnerPartId=-1|LineWidth=1|Color=8388608|LocationCount=3|X1=950|Y1=540|X2=990|Y2=540|X3=990|Y3=480
|RECORD=27|IndexInSheet=127|OwnerPartId=-1|LineWidth=1|Color=8388608|LocationCount=2|X1=780|Y1=840|X2=720|Y2=840
|RECORD=27|IndexInSheet=128|OwnerPartId=-1|LineWidth=1|Color=8388608|LocationCount=2|X1=780|Y1=830|X2=720|Y2=830
|RECORD=27|IndexInSheet=129|OwnerPartId=-1|LineWidth=1|Color=8388608|LocationCount=2|X1=720|Y1=820|X2=780|Y2=820
|RECORD=27|IndexInSheet=130|OwnerPartId=-1|LineWidth=1|Color=8388608|LocationCount=3|X1=680|Y1=370|X2=720|Y2=370|X3=720|Y3=360
|RECORD=27|IndexInSheet=131|OwnerPartId=-1|LineWidth=1|Color=8388608|LocationCount=3|X1=680|Y1=310|X2=720|Y2=310|X3=720|Y3=320
|RECORD=27|IndexInSheet=132|OwnerPartId=-1|LineWidth=1|Color=8388608|LocationCount=4|X1=720|Y1=310|X2=750|Y2=310|X3=750|Y3=320|X4=810|Y4=320
|RECORD=27|IndexInSheet=133|OwnerPartId=-1|LineWidth=1|Color=8388608|LocationCount=4|X1=810|Y1=330|X2=750|Y2=330|X3=750|Y3=370|X4=720|Y4=370
|RECORD=27|IndexInSheet=134|OwnerPartId=-1|LineWidth=1|Color=8388608|LocationCount=3|X1=810|Y1=270|X2=780|Y2=270|X3=780|Y3=250
|RECORD=27|IndexInSheet=135|OwnerPartId=-1|LineWidth=1|Color=8388608|LocationCount=2|X1=780|Y1=270|X2=780|Y2=390
|RECORD=27|IndexInSheet=136|OwnerPartId=-1|LineWidth=1|Color=8388608|LocationCount=3|X1=930|Y1=270|X2=970|Y2=270|X3=970|Y3=190
|RECORD=27|IndexInSheet=137|OwnerPartId=-1|LineWidth=1|Color=8388608|LocationCount=2|X1=780|Y1=190|X2=780|Y2=220
|RECORD=27|IndexInSheet=138|OwnerPartId=-1|LineWidth=1|Color=8388608|LocationCount=2|X1=1020|Y1=330|X2=990|Y2=330
|RECORD=27|IndexInSheet=139|OwnerPartId=-1|LineWidth=1|Color=8388608|LocationCount=2|X1=950|Y1=330|X2=930|Y2=330
|RECORD=27|IndexInSheet=140|OwnerPartId=-1|LineWidth=1|Color=8388608|LocationCount=2|X1=1020|Y1=810|X2=960|Y2=810
|RECORD=27|IndexInSheet=141|OwnerPartId=-1|LineWidth=1|Color=8388608|LocationCount=2|X1=960|Y1=800|X2=1020|Y2=800
|RECORD=17|IndexInSheet=142|OwnerPartId=-1|ShowNetName=T|Location.X=700|Location.Y=600|Orientation=2|Color=255|FontID=1|Text=FPGA_MAC_PPS_IN1-|IsCrossSheetConnector=T
|RECORD=29|IndexInSheet=-1|OwnerPartId=-1|Location.X=720|Location.Y=310|Color=128
|RECORD=29|IndexInSheet=-1|OwnerPartId=-1|Location.X=720|Location.Y=370|Color=128
|RECORD=29|IndexInSheet=-1|OwnerPartId=-1|Location.X=740|Location.Y=600|Color=128
|RECORD=29|IndexInSheet=-1|OwnerPartId=-1|Location.X=750|Location.Y=920|Color=128
|RECORD=29|IndexInSheet=-1|OwnerPartId=-1|Location.X=770|Location.Y=570|Color=128
|RECORD=29|IndexInSheet=-1|OwnerPartId=-1|Location.X=780|Location.Y=270|Color=128
|RECORD=29|IndexInSheet=-1|OwnerPartId=-1|Location.X=810|Location.Y=540|Color=128
|RECORD=29|IndexInSheet=-1|OwnerPartId=-1|Location.X=980|Location.Y=740|Color=128
|RECORD=29|IndexInSheet=-1|OwnerPartId=-1|Location.X=980|Location.Y=750|Color=128
|RECORD=29|IndexInSheet=-1|OwnerPartId=-1|Location.X=1100|Location.Y=920|Color=128
|RECORD=29|IndexInSheet=-1|OwnerPartId=-1|Location.X=1150|Location.Y=870|Color=128
|RECORD=29|IndexInSheet=-1|OwnerPartId=-1|Location.X=1150|Location.Y=920|Color=128